TITLE: Bill of Materials
DATE: 01/07/2023
DESIGN: s9s_mb_2u
TEMPLATE: C:\Cadence\SPB_17.2\share\cdssetup\template.bom
CALLOUT: 

S.No.,PART_NUMBER,DESCRIPTION,MATERIAL,Qty,MANUFTR,MANUF_PN,Ref Des,QPN,LIFECYCLE,STANDARD,ROOM1,ROOM
0,AJ004400000,IC OTHER(100P)9SQ440NQQI8(QFN),IC,1,IDT,9SQ440NQQI8,U13,?,?,?,?,?
1,AJ020010003,IC OTHER(80P)9QXL2001BNHGI8(GQFN),IC,1,IDT,9QXL2001BNHGI8,U38,?,?,?,?,?
2,AJ094000T08,IC(484P)LCMXO3LF-9400C-5BG484C(CABGA),IC,1,LSC,LCMXO3LF-9400C-5BG484C,U249,?,?,?,?,?
3,AJ0QV2N0T00,IC CTRL(749P)EMMITSBURG-QV2N(FCBGA),IC,1,INT,GFNOCPU04302300-QV2N-MM#99A1WT,U4,?,?,?,?,?
4,AKE30Z00613,IC(8P) EEPROM M24128-BWMN6TP(SO8),IC,1,SGT,M24128-BWMN6TP,U64,?,?,?,?,?
5,AL000125003,IC OTHER(24P)DS125BR111RTWR(WQFN),EMPTY,1,TIC,DS125BR111RTWR,U328,?,?,?,?,PCIE REDRIVER1_BOM2
6,AL000128K00,IC OTHER(16P)ADC128D818CIMTX/NOPB(TSSOP),IC,1,TIC,ADC128D818CIMTX/NOPB,U269,?,?,?,?,ADC1_BOM2
7,AL000183000,IC AMPL(5P)INA183A1IDBVR(SOT23),EMPTY,2,TIC,INA183A1IDBVR,"U102,U103",?,?,?,?,?
8,AL000211007,IC OTHER(12P) TUSB211IRWBR(QFN),EMPTY,1,TIC,TUSB211IRWBR,U312,?,?,?,?,?
9,AL000211007,IC OTHER(12P) TUSB211IRWBR(QFN),EMPTY,1,TIC,TUSB211IRWBR,U5201,?,?,?,?,USB1_BOM2
10,AL000230001,IC OTHER (16P) INA230AIRGTR (QFN 3X3),IC,5,TIC,INA230AIRGTR,"U263,U264,U265,U266,U276",?,?,?,?,?
11,AL000230001,IC OTHER (16P) INA230AIRGTR (QFN 3X3),EMPTY,1,TIC,INA230AIRGTR,U331,?,?,?,?,HSC1_BOM2
12,AL000251001,IC OTHER(24P)9FGL0251CKILFT(VFQFPN),IC,1,RTT,9FGL0251CKILFT,U247,?,End of Life,Non-Preferred,?,?
13,AL000257W24,IC OTHER(16P)QS3VH257QG8(QSOP),IC,2,?,?,"U14,U15",?,?,?,?,?
14,AL000304K01,IC OTHER(8P) PI6CV304LE(TSSOP),IC,1,PIM,PI6CV304LE,U90,?,?,?,?,?
15,AL000331011,IC OTHER(5P) AP331AWG-7 (SOT25),EMPTY,4,DDS,AP331AWG-7,"U339,U340,U342,U344",?,?,?,?,?
16,AL000451003,IC OTHER(32P) 9ZXL0451EKILFT(VFQFPN),IC,1,IDT,9ZXL0451EKILFT,U314,?,?,?,?,?
17,AL000682001,IC CTRL(13P)NB682GD-Z(QFN),IC,1,MPS,NB682GD-Z,PU74,?,?,?,?,?
18,AL000852001,IC CTRL(28P) GL852G-OHY60(QFN),IC,1,GSL,GL852G-OHY60,U268,?,?,?,?,USB1_BOM1
19,AL000852001,IC CTRL(28P) GL852G-OHY60(QFN),EMPTY,1,GSL,GL852G-OHY60,U313,?,?,?,?,?
20,AL001002007,IC OTHERS(24P) PI3EQX1002EZREX(TQFN),IC,1,DDS,PI3EQX1002EZREX,U309,?,?,?,?,?
21,AL001086001,IC OTHER(6P)ADM1086AKSZ-REEL7(SC70),IC,1,ADV,ADM1086AKSZ-REEL7,U94,?,Comp-Approve,End of Design,?,DELAY1_BOM1
22,AL001G66000,IC(5P) 74LVC1G66GV(SOT753),IC,3,PHI,74LVC1G66GV,"U16,U320,U321",?,?,?,?,?
23,AL002014K01,IC OTHER(14P) GTL2014PW(TSSOP),IC,6,NXP,GTL2014PW,"U83,U84,U301,U304,U305,U306",?,?,?,?,?
24,AL002267000,IC(10P)NX3L2267GM(XQFN),IC,2,NXP,NX3L2267GM,"U96,U97",?,?,?,?,?
25,AL002G07003,IC OTHER(6P)74LVC2G07DW-7(SOT-363),IC,8,DDS,74LVC2G07DW-7,"U58,U59,U134,U211,U212,U255,U257,U308",?,?,?,?,?
26,AL002G07003,IC OTHER(6P)74LVC2G07DW-7(SOT-363),EMPTY,1,DDS,74LVC2G07DW-7,U332,?,?,?,?,?
27,AL002G07006,IC(6P) SN74LVC2G07DCKR(SC70-6),IC,1,?,SN74LVC2G07DCKR,U259,?,Comp-Approve,End of Design,?,?
28,AL003126K08,IC OTHER(14P) 74CBTLV3126PW(TSSOP),IC,8,NXP,74CBTLV3126PW,"U17,U18,U67,U68,U86,U222,U223,U327",?,?,?,?,?
29,AL003700002,IC OTHER(6P)TPS3700DDCR(SOT-23-THIN),EMPTY,2,TIC,TPS3700DDCR,"U205,U369",?,?,?,?,?
30,AL003889000,IC OTHER(37P) IR3889MTRPBF(QFN),IC,1,SNI,IR3889MTRPBF,PU9,?,?,?,?,?
31,AL003895003,IC OTHER(6P)TPS3895ADRYR(SON),EMPTY,1,TIC,TPS3895ADRYR,U117,?,?,?,?,DELAY1_BOM2
32,AL004307000,IC OTHER(8P) LTC4307CMS8#TRPBF(MSOP),IC,4,LIN,LTC4307CMS8#TRPBF,"U175,U192,U194,U200",?,?,?,?,?
33,AL004307000,IC OTHER(8P) LTC4307CMS8#TRPBF(MSOP),EMPTY,1,LIN,LTC4307CMS8#TRPBF,U176,?,?,?,?,?
34,AL005016007,IC (10P) MP5016GQH-L-Z(QFN),EMPTY,2,MPS,MP5016GQH-L-Z,"PU205,PU207",?,?,?,?,NIC1_P3V3_BOM2
35,AL005016007,IC (10P) MP5016GQH-L-Z(QFN),EMPTY,1,MPS,MP5016GQH-L-Z,PU293,?,?,?,?,E1S1_P3V3_BOM2
36,AL005990A03,IC(45P)MP5990GMA-1111-Z(LGA),IC,1,MPS,MP5990GMA-1111-Z,PU289,?,?,?,?,HSC1_BOM1
37,AL005991A00,IC(32P)MP5991GLU-Z(LGA),IC,4,MPS,MP5991GLU-Z,"PU287,PU288,PU296,PU297",?,?,?,?,HSC1_BOM1
38,AL006700001,IC OTHER(6P)LT6700CS6-1#TRPBF(TSOT-23),IC,1,LIN,LT6700CS6-1#TRPBF,U206,?,?,?,?,?
39,AL0075BD000,IC OTHER (8P) LM75BD(SO8),IC,4,NXP,LM75BD,"U270,U271,U272,U273",?,?,?,?,?
40,AL007718001,IC OTHER(8P) NCT7718W(MSOP),EMPTY,1,NVT,NCT7718W,U345,?,?,?,?,HSC1_BOM2
41,AL009306K04,IC OTHER(8P)PCA9306DP1(TSSOP),IC,1,NXP,PCA9306DP1,U98,?,?,?,?,?
42,AL009517000,IC OTHER (8P) I2C PCA9517AD (SO8),IC,2,NXP,PCA9517AD,"U30,U31",?,?,?,?,?
43,AL009539K07,IC OTHER(24P)PCA9539RPW(TSSOP),IC,1,NXP,PCA9539RPW,U181,?,?,?,?,?
44,AL009545K17,IC (20P) PCA9545APW (TSSOP),IC,1,PHI,PCA9545APW,U143,?,?,?,?,?
45,AL009548K02,IC OTHER(24P) TCA9548APWR(TSSOP),IC,2,TIC,TCA9548APWR,"U36,U39",?,?,?,?,?
46,AL009555K07,IC OTHER(24P)PCA9555APW(TSSOP),IC,2,NXP,PCA9555APW,"U51,U209",?,?,?,?,?
47,AL009617K02,IC OTHER(8P) PCA9617ADP(TSSOP),IC,6,NXP,PCA9617ADP,"U28,U29,U235,U236,U279,U315",?,?,?,?,?
48,AL009818001,IC OTHER(3P)RT9818C-44GV(SOT23-3),IC,1,RTK,RT9818C-44GV,U99,?,?,?,?,?
49,AL011617W00,IC CTRL(16P)MAX11617EEE+T QSOP,EMPTY,1,MAM,MAX11617EEE+T,U193,?,?,?,?,ADC1_BOM1
50,AL012902001,IC OTHER(30P)PI3EQX12902AZLEX(TQFN),IC,1,PIM,PI3EQX12902AZLEX,U237,?,?,?,?,PCIE REDRIVER1_BOM1
51,AL015080B00,IC OTHER(28P)MAX15090BEWI+T(WLP),IC,2,MAM,MAX15090BEWI+T,"PU200,PU202",?,?,?,?,NIC1_P3V3_BOM1
52,AL015080B00,IC OTHER(28P)MAX15090BEWI+T(WLP),EMPTY,2,MAM,MAX15090BEWI+T,"PU201,PU203",?,?,?,NIC1_P12V_MAM_TIC_BOM2,NIC1_P12V_MAM_MAM_BOM1
53,AL015080B00,IC OTHER(28P)MAX15090BEWI+T(WLP),EMPTY,1,MAM,MAX15090BEWI+T,PU294,?,?,?,E1S1_P12V_MAM_TIC_BOM2,E1S1_P12V_MAM_MAM_BOM1
54,AL015080B00,IC OTHER(28P)MAX15090BEWI+T(WLP),IC,1,MAM,MAX15090BEWI+T,PU295,?,?,?,?,E1S1_P3V3_BOM1
55,AL015080B00,IC OTHER(28P)MAX15090BEWI+T(WLP),EMPTY,1,MAM,MAX15090BEWI+T,PU300,?,?,?,?,SCM_P12V_BOM1
56,AL031312000,IC(22P)RS31312R(QFN),IC,2,RDS,RS31312R,"PU204,PU206",?,?,?,NIC1_P12V_MPS_TIC_BOM4,NIC1_P12V_MPS_MAM_BOM3
57,AL031312000,IC(22P)RS31312R(QFN),IC,1,RDS,RS31312R,PU292,?,?,?,E1S1_P12V_MPS_TIC_BOM4,E1S1_P12V_MPS_MAM_BOM3
58,AL031312000,IC(22P)RS31312R(QFN),IC,1,RDS,RS31312R,PU299,?,?,?,?,SCM_P12V_BOM2
59,AL053317005,IC(14P)RS53317LR(QFN),IC,2,RDS,RS53317LR,"PU81,PU82",?,?,?,?,?
60,AL053318002,IC(21P)RS53318LR(QFN),IC,3,RDS,RS53318LR,"PU79,PU80,PU181",?,?,?,?,?
61,AL053319002,IC(21P)RS53319LR(QFN),IC,1,RDS,RS53319LR,PU73,?,?,?,?,?
62,AL069260000,IC CTRL(40P)ISL69260IRAZ-T(QFN),IC,4,RTT,ISL69260IRAZ-T,"PU5,PU18,PU22,PU35",?,?,?,?,?
63,AL080929000,IC OTHER(3P) APX809-29SAG-7(SOT23),IC,4,DDS,APX809-29SAG-7,"U52,U216,U330,U336",?,?,?,?,?
64,AL099390004,IC CTRL(41P) ISL99390FRZ-TR5935(QFN),IC,30,RTT,ISL99390FRZ-TR5935,"PU6_P0_8,PU7_P0_7,PU8_P0_6,PU9_P0_5,PU10_P0_4,PU11_P0_3,PU12_P0_2,PU13_P0_1,PU17,PU23_P1_8,PU24_P1_7,PU25_P1_6,PU26_P1_5,PU27_P1_4,PU28_P1_3,PU30_P1_2,PU31_P1_1,PU36,PU43_P0_1,PU44_P0_2,PU50_P1_1,PU51_P1_2,PU69_P0_1,PU70_P0_2,PU71_P0_3,PU72_P0_4,PU75_P1_1,PU76_P1_2,PU77_P1_3,PU78_P1_4",?,?,?,?,?
65,AL1G0007001,IC OTHER(5P) 74LVC1G07GV(SOT753),IC,4,NXP,74LVC1G07GV,"U104,U157,U218,U219",?,?,?,?,?
66,AL1G0008020,IC OTHER(5P) 74LVC1G08W5-7(SOT25),IC,9,DDS,74LVC1G08W5-7,"U50,U53,U208,U210,U278,U322,U323,U334,U335",?,?,?,?,?
67,AL1G0017K01,IC OTHER(5P) 74LVC1G17GW(TSSOP),IC,2,NXP,74LVC1G17GW,"U75,U207",?,?,?,?,?
68,AL1G0126009,IC OTHER(5P) 74LVC1G126SE-7 (SOT353),IC,9,DDS,74LVC1G126SE-7,"U66,U82,U145,U204,U217,U224,U225,U239,U286",?,?,?,?,?
69,AL1G07SE000,IC OTHER(5P)74LVC1G07SE-7(SOT353),IC,2,DDS,74LVC1G07SE-7,"U95,U154",?,?,?,?,?
70,AL221340002,IC (29P) RAA2213404GNP#HB0(PQFN),IC,2,RTT,RAA2213404GNP#HB0,"PU42,PU49",?,?,?,?,?
71,AL229126000,IC CTRL(48P)RAA229126GNP#HA0(QFN),IC,2,RTT,RAA229126GNP#HA0,"PU14,PU29",?,?,?,?,?
72,AL2G0017005,IC(6P) 74LVC2G17GW (SC-88),IC,7,PHI,74LVC2G17GW,"U150,U195,U196,U252,U253,U256,U316",?,?,?,?,?
73,AL404025013,IC OTHER(3P)LM4040AIM3X-2.5/NOPB(SOT23),EMPTY,4,TIC,LM4040AIM3X-2.5/NOPB,"U337,U338,U341,U343",?,?,?,?,?
74,ALSB3157000,IC(6P) NC7SB3157P6X(SC70-6),IC,6,?,NC7SB3157P6X,"U21,U22,U60,U61,U85,U142",?,Comp-Approve,End of Design,?,?
75,ALSB3157000,IC(6P) NC7SB3157P6X(SC70-6),EMPTY,4,?,NC7SB3157P6X,"U243,U244,U245,U246",?,Comp-Approve,End of Design,?,?
76,ALVC1G02000,IC(5P) 74LVC1G02GW(SOT353),IC,1,?,?,U23,?,?,?,?,?
77,ALVC1G32007,IC(5P)74LVC1G32GW (SC70-5),IC,1,?,?,U248,?,?,?,?,?
78,ALVC2G08K01,IC OTHER(8P) 74LVC2G08DP(TSSOP),IC,3,NXP,74LVC2G08DP,"U240,U241,U242",?,?,?,?,?
79,BA008470026,"TRANS SMD BC847BPN(45V,0.1A,0.3W)",IC,6,NXE,BC847BPN,"Q138,Q139,Q140,Q141,Q142,Q143",?,?,?,?,?
80,BA039040039,"TRANS SMD MMBT3904(40V,200MA)SOT23",EMPTY,1,?,?,U365,?,Comp-Approve,End of Design,?,HSC1_BOM2
81,BAM138K0000,"TRANS MOS BSS138K(50V,0.22A,0.35W)",EMPTY,2,?,BSS138K,"PU173,PU174",?,Comp-Approve,End of Design,?,?
82,BAM138K0000,"TRANS MOS BSS138K(50V,0.22A,0.35W)",IC,7,?,BSS138K,"U49,U70,U87,U89,U215,U307,U325",?,Comp-Approve,End of Design,?,?
83,BAM138K0003,"TRANS MOSFET PJT138K(50V,0.36A,0.236W)",IC,52,PJT,PJT138K,"Q15,Q16,Q37,Q50,Q67,Q69,Q70,Q71,Q72,Q74,Q75,Q76,Q77,Q78,Q79,Q80,Q81,Q83,Q84,Q85,Q86,Q87,Q88,Q95,Q96,Q101,Q102,Q103,Q104,Q106,Q107,Q108,Q128,Q129,Q130,Q131,Q132,Q133,Q134,Q135,Q136,Q137,Q144,Q145,Q146,Q148,Q150,Q151,Q152,Q153,Q154,Q236",?,?,?,?,?
84,BAM138K0003,"TRANS MOSFET PJT138K(50V,0.36A,0.236W)",EMPTY,2,PJT,PJT138K,"Q118,Q123",?,?,?,NIC1_P12V_MAM_TIC_BOM2,NIC1_P12V_MAM_MAM_BOM1
85,BAM138K0003,"TRANS MOSFET PJT138K(50V,0.36A,0.236W)",IC,2,PJT,PJT138K,"Q119,Q124",?,?,?,?,NIC1_P3V3_BOM1
86,BAM138K0003,"TRANS MOSFET PJT138K(50V,0.36A,0.236W)",EMPTY,1,PJT,PJT138K,Q125,?,?,?,?,SCM_P12V_BOM1
87,BAM138K0003,"TRANS MOSFET PJT138K(50V,0.36A,0.236W)",IC,1,PJT,PJT138K,Q126,?,?,?,?,E1S1_P3V3_BOM1
88,BAM138K0003,"TRANS MOSFET PJT138K(50V,0.36A,0.236W)",EMPTY,1,PJT,PJT138K,Q127,?,?,?,E1S1_P12V_MAM_TIC_BOM2,E1S1_P12V_MAM_MAM_BOM1
89,BAM60080000,"TRANS MOS NX6008NBKS(60V, 0.22A,260W)",IC,5,NXE,NX6008NBKS,"Q97,Q98,Q99,Q100,Q105",?,?,?,?,?
90,BAM70020002,"TR MOSFET 2N7002K(60V,300MA,0.35W)SOT-23",IC,11,PJT,2N7002K,"Q33,Q34,Q35,Q39,Q46,Q52,Q53,Q54,U158,U290,U324",?,?,?,?,?
91,BAM70020002,"TR MOSFET 2N7002K(60V,300MA,0.35W)SOT-23",EMPTY,1,PJT,2N7002K,U329,?,?,?,?,?
92,BAMNR580000,"TRANS MOS PSMNR58-30YLH(30V,380A,333W)",EMPTY,7,NXE,PSMNR58-30YLH,"PPQ1,PPQ2,PPQ5,PPQ6,PPQ7,PPQ8,PPQ9",?,?,?,?,HSC1_BOM2
93,BAMNR580000,"TRANS MOS PSMNR58-30YLH(30V,380A,333W)",IC,2,NXE,PSMNR58-30YLH,"Q56,Q57",?,?,?,?,?
94,BC000340033,"DIODE SMD SDMK0340L-7-F(40V,30MA)",IC,1,?,?,D145,?,?,?,?,?
95,BC000340Z30,"DIODE SMD B340A-13-F(40V,3A)SCHOTTKY",IC,7,DDS,B340A-13-F,"PD102,PD103,PD108,PD109,PD112,PD113,PD116",?,?,?,?,?
96,BC000530Z41,"DIODE SMD B0530WS-7-F(30V,0.5A)SOD-323",IC,8,DDS,B0530WS-7-F,"D42,D43,D44,D45,D46,D47,D48,D49",?,Comp-Approve,End of Design,?,?
97,BC005819Z40,DIODE SMD 1N5819HW-7-F(40V.1A.SOD123),IC,1,DDS,1N5819HW-7-F,D141,?,Comp-Approve,End of Design,?,?
98,BC015P3SZ00,"DIODE SMD SS15P3S-M3/86A(30V,15A)",IC,1,SIL,SS15P3S-M3/86A,PD17,?,?,?,?,?
99,BC0BAS70Z01,"DIODE SMD BAS70-05-7-F(70V,SHTKY,SOT-23)",IC,1,DDS,BAS70-05-7-F,U62,?,Comp-Approve,End of Design,?,?
100,BC0BAT54Z53,DIODE BAT54-7-F(30V.200MA SCHOTTKY),IC,1,DDS,BAT54-7-F,D7,?,?,?,?,?
101,BC0MDJ14000,"DIODE SMD 5.0SMDJ14A(14V,216A,5000W)",IC,2,LFI,5.0SMDJ14A,"PD15,PD16",?,?,?,?,?
102,BCSMF14AZ01,"DIODE SMF14A(14V,8.6A)SOD-123FL",IC,4,LFI,SMF14A,"PD101,PD107,PD114,PD115",?,?,?,?,?
103,BEBL0172Z00,LED SMD(2P) BLUE(LTST-C281TBKT-5A),IC,38,?,LTST-C281TBKT-5A,"D0,D65,D66,D67,D68,D69,D70,D71,D72,D73,D74,D75,D76,D77,D78,D79,D80,D81,D82,D83,D84,D85,D86,D87,D88,D89,D90,D91,D92,D93,D94,D95,D96,D97,D98,D99,D142,D143",?,?,?,?,?
104,BEYL0159Z00,LED SMD(2P)YELLOW(LTST-C190KSKT-P),IC,2,?,LTST-C190KSKT-P,"D6,D144",?,?,?,?,?
105,BF625000014,"OSC SMD 25MHZ(+-25PPM,3.3V)FJ2500009",OSC,1,?,?,OSC2,?,?,?,?,?
106,BF650000032,"OSC SMD 50MHZ(25PPM,15PF,3.3V)FK5000023",OSC,1,?,?,OSC1,?,?,?,?,?
107,BG6120000E0,"XTAL 12MHZ(+-20PPM,10PF)E2SB12E00000EE",MISC,1,HHE,E2SB12E00000EE,Y4,?,?,?,?,USB1_BOM1
108,BG6120000E0,"XTAL 12MHZ(+-20PPM,10PF)E2SB12E00000EE",EMPTY,1,HHE,E2SB12E00000EE,Y9,?,?,?,?,?
109,BG6250000F0,"XTAL SMD 25MHZ(+-10PPM,8PF)FL2500498",MISC,2,DDS,FL2500498,"Y2,Y3",?,?,?,?,?
110,BG625000802,"XTAL SMD 25MHZ(+-20PPM,20PF)7M25020008",EMPTY,1,TXC,7M25020008,Y7,?,?,?,?,?
111,BG632768012,"CRYSTAL SMD 32.768KHZ(+-20PPM,12.5PF)",IC,1,?,?,Y1,?,Comp-Approve,End of Design,?,?
112,CC71003MZ30,"CAP OSCON SMD 100U 16V(20%,5*5.8)NPN",OSCON,1,?,?,PC1215,?,?,?,?,?
113,CC72201MZ28,"CAP OSCON SMD 220U 6.3V(20%,5*5.8)NPN",ALUM,1,?,?,PC1845,?,?,?,?,?
114,CC72703MD38,"CAPOSCON DIP 270U16V(20%,ESR10,6.3*8)NPN",OSCON,20,?,?,"PC3,PC207,PC208,PC315,PC318,PC321,PC324,PC417,PC460,PC461,PC566,PC579,PC582,PC585,PC588,PC622,PC1189,PC1210,PC2345,PC2346",?,?,?,?,?
115,CC75601MD16,"CAP OSCON DIP 560U 6.3V(+-20%,6.3*8)NPN",OSCON,4,?,?,"PC1258,PC1771,PC1866,PC1867",?,?,?,?,?
116,CC7560JMD16,"CAP OSCON DIP 560U 2.5V(20%,5*8)SAY",OSCON,36,?,?,"PC16,PC83,PC316,PC319,PC322,PC325,PC384,PC385,PC414,PC415,PC416,PC580,PC583,PC586,PC589,PC619,PC620,PC621,PC1183,PC1185,PC1186,PC1201,PC1203,PC1204,PC1227,PC1230,PC1574,PC1576,PC1579,PC1593,PC1595,PC1596,PC1644,PC1645,PC2180,PC2199",?,Comp-Approve,End of Design,?,?
117,CH-8216TB09,CAP CHIP 8.2P 50V (+-0.1P NP0 0402),NP0,4,?,?,"C2036,C2037,C2255,C2256",?,?,?,?,?
118,CH01206JB05,CAP CHIP 12P 50V(+-5%.C0G.0402),EMPTY,2,?,?,"C2326,C2327",?,?,?,?,?
119,CH01806JB07,CAP CHIP 18P 50V(+-5% C0G 0402),C0G,2,?,?,"C1507,C1508",?,?,?,?,?
120,CH01806JB07,CAP CHIP 18P 50V(+-5% C0G 0402),C0G,2,?,?,"C2029,C2030",?,?,?,?,USB1_BOM1
121,CH02706JB06,CAP CHIP 27P 50V(+-5% NPO 0402)          ,EMPTY,2,?,?,"C103,C104",?,?,?,?,?
122,CH0396J0B04,"CAP CHIP 39P 50V(+-5%,NPO,0402)MUR",EMPTY,2,?,?,"PC2157,PC2168",?,?,?,?,NIC1_P3V3_BOM2
123,CH0396J0B04,"CAP CHIP 39P 50V(+-5%,NPO,0402)MUR",EMPTY,1,?,?,PC2197,?,?,?,?,E1S1_P3V3_BOM2
124,CH04706JB01,CHIP0402,NPO,1,?,?,PC1877,?,?,?,?,?
125,CH11006JB00,"CAP CHIP 100P 50V(+-5%,NPO,0402)",NPO,2,?,?,"C1209,C1211",?,?,?,?,?
126,CH11006JB18,CAP CHIP 100P 50V(+-5%.X7R.0402),EMPTY,8,?,?,"C1344,C2042,C2043,C2044,C2045,C2175,C2176,C2195",?,Comp-Approve,End of Design,?,ADC1_BOM1
127,CH11006JB18,CAP CHIP 100P 50V(+-5%.X7R.0402),EMPTY,2,?,?,"PC1322,PC2162",?,Comp-Approve,End of Design,?,NIC1_P3V3_BOM2
128,CH11006JB18,CAP CHIP 100P 50V(+-5%.X7R.0402),X7R,1,?,?,PC2167,?,Comp-Approve,End of Design,NIC1_P12V_MPS_TIC_BOM4,NIC1_P12V_MPS_MAM_BOM3
129,CH11006JB18,CAP CHIP 100P 50V(+-5%.X7R.0402),EMPTY,1,?,?,PC2203,?,Comp-Approve,End of Design,?,E1S1_P3V3_BOM2
130,CH12206KB14,"CAP CHIP 220P 50V(+-10%,X7R,0402)",X7R,1,?,?,PC2182,?,?,?,?,HSC1_BOM1
131,CH12206KB14,"CAP CHIP 220P 50V(+-10%,X7R,0402)",EMPTY,3,?,?,"PC2183,PC2224,PC2225",?,?,?,?,?
132,CH12206KB14,"CAP CHIP 220P 50V(+-10%,X7R,0402)",X7R,1,?,?,PC569,?,?,?,?,?
133,CH14706KB18,CHIP0402,X7R,10,?,?,"PC100,PC101,PC222,PC336,PC393,PC475,PC554,PC631,PC1271,PC1292",?,?,?,?,?
134,CH1566K1B09,"CAP CHIP 560P 50V(+-10%,X7R,0402)",X7R,1,?,?,PC2340,?,?,?,?,SCM_P12V_BOM2
135,CH1566K1B09,"CAP CHIP 560P 50V(+-10%,X7R,0402)",X7R,1,?,?,PC2341,?,?,?,E1S1_P12V_MPS_TIC_BOM4,E1S1_P12V_MPS_MAM_BOM3
136,CH16806KB17,"CAP CHIP 680P 50V(+-10%,X7R,0402)",X7R,4,?,?,"PC237,PC238,PC1223,PC1266",?,?,?,?,?
137,CH1686K1B09,"CAP CHIP 680P 50V(+-10%,X7R,0402)MUR",X7R,1,?,?,PC1253,?,?,?,?,?
138,CH21006JB10,"CAP CHIP 1000P 50V(+-5%,X7R,0402)",X7R,12,?,?,"C1296,C1297,C1301,C2446,C2451,C2452,C2460,C2860,C3267,C3268,C3274,C3275",?,?,?,?,?
139,CH21006JB10,"CAP CHIP 1000P 50V(+-5%,X7R,0402)",EMPTY,46,?,?,"C626,C1300,C1307,C1308,C1754,C1756,C1772,C1773,C1774,C1802,C1804,C1881,C1973,C1974,C1975,C1976,C1978,C1988,C2264,C2265,C2266,C2267,C2268,C2269,C2270,C2271,C2272,C2273,C2340,C2342,C2343,C2372,C2373,C2374,C2391,C2445,C2447,C2450,C2453,C2454,C2859,C3266,C3269,C3273,C3276,PC2286",?,?,?,?,?
140,CH21006K917,"CAP CHIP 1000P 50V(+-10%,X7R,0603)",EMPTY,1,?,?,C2459,?,Comp-Approve,End of Design,?,HSC1_BOM2
141,CH21006KB16,"CAP CHIP 1N 50V(+-10%,X7R,0402)EP",EMPTY,5,?,?,"PC1751,PC2347,PC2348,PC2349,PC2350",?,?,?,?,?
142,CH2336K1B12,CHIP0402,X7R,44,?,?,"PC27,PC28,PC176,PC189_P0_1,PC190_P0_2,PC215,PC216,PC230_P0_8,PC231_P0_7,PC252_P0_6,PC253_P0_5,PC274_P0_4,PC275_P0_3,PC296_P0_2,PC297_P0_1,PC331,PC374,PC389,PC397_P1_1,PC398_P1_2,PC422,PC429,PC442_P1_1,PC443_P1_2,PC468,PC469,PC483_P1_8,PC484_P1_7,PC505_P1_6,PC506_P1_5,PC527_P1_4,PC528_P1_3,PC549,PC560_P1_2,PC561_P1_1,PC594,PC602_P0_1,PC603_P0_2,PC627,PC634,PC1173_P0_3,PC1174_P0_4,PC1193_P1_3,PC1194_P1_4",?,?,?,?,?
143,CH23906KB14,"CAP CHIP 3900P 50V(+-10%,X7R,0402)",EMPTY,2,?,?,"PC2150,PC4056",?,?,?,NIC1_P12V_MAM_TIC_BOM2,NIC1_P12V_MAM_MAM_BOM1
144,CH23906KB14,"CAP CHIP 3900P 50V(+-10%,X7R,0402)",EMPTY,1,?,?,PC2215,?,?,?,E1S1_P12V_MAM_TIC_BOM2,E1S1_P12V_MAM_MAM_BOM1
145,CH23906KB14,"CAP CHIP 3900P 50V(+-10%,X7R,0402)",EMPTY,1,?,?,PC2237,?,?,?,?,SCM_P12V_BOM1
146,CH2686K1B01,"CAP CHIP 6800P 50V(+-10%,X7R,0402)",X7R,2,?,?,"PC2089,PC2151",?,?,?,?,NIC1_P3V3_BOM1
147,CH2686K1B01,"CAP CHIP 6800P 50V(+-10%,X7R,0402)",X7R,1,?,?,PC2216,?,?,?,?,E1S1_P3V3_BOM1
148,CH30106KB19,"CAP CHIP 0.001U 50V(10%,X7R,0402)",X7R,1,?,?,PC2192,?,Comp-Release Qty,End of Design,?,HSC1_BOM1
149,CH31004KB17,"CAP CHIP 0.01U 25V(+-10%,X7R,0402)",X7R,5,?,?,"PC1420,PC1421,PC2277,PC2279,PC2282",?,Comp-Release Qty,End of Design,?,?
150,CH31006KB18,"CAP CHIP 0.01U 50V(+-10%,X7R,0402)",X7R,44,?,?,"C1113,C1118,C1124,C1127,C1133,C1138,C1142,C1146,C1152,C1154,C1893,C1894,C1895,C1896,C1897,C1898,C1899,C1900,C1901,C1902,C1903,C1904,C1908,C1909,C1910,C1911,C1912,C1913,C1914,C1915,C1916,C1917,C1918,C1919,C1926,C1927,C1928,C1929,C1930,C1931,C1932,C1933,C1934,C2287",?,?,?,?,?
151,CH31006KB18,"CAP CHIP 0.01U 50V(+-10%,X7R,0402)",EMPTY,7,?,?,"C2148,PC2088,PC2144,PC2149,PC2213,PC2214,PC2236",?,?,?,?,?
152,CH31006KB18,"CAP CHIP 0.01U 50V(+-10%,X7R,0402)",X7R,2,?,?,"PC2189,PC2190",?,?,?,?,HSC1_BOM1
153,CH32203KB11,"CAP CHIP 0.022U 16V(+-10%,X7R,0402)",X7R,3,?,?,"PC2000,PC2001,PC2002",?,?,?,?,?
154,CH3334K1B00,"CAP CHIP 33NF 25V(+-10%,X7R,0402)",EMPTY,1,?,?,PC1750,?,?,?,?,?
155,CH3474K1B04,CAP CHIP 0.047U 25V(+-10% X7R 0402),X7R,12,?,?,"C110,C111,C112,C114,C115,C116,C117,C119,C120,C171,C173,C1316",?,?,?,?,?
156,CH3474K1B04,CAP CHIP 0.047U 25V(+-10% X7R 0402),X7R,2,?,?,"PC2155,PC2166",?,?,?,NIC1_P12V_MPS_TIC_BOM4,NIC1_P12V_MPS_MAM_BOM3
157,CH3474K1B04,CAP CHIP 0.047U 25V(+-10% X7R 0402),X7R,1,?,?,PC2193,?,?,?,?,HSC1_BOM1
158,CH3474K1B04,CAP CHIP 0.047U 25V(+-10% X7R 0402),X7R,1,?,?,PC2232,?,?,?,?,SCM_P12V_BOM2
159,CH3474K1B04,CAP CHIP 0.047U 25V(+-10% X7R 0402),X7R,1,?,?,PC2281,?,?,?,E1S1_P12V_MPS_TIC_BOM4,E1S1_P12V_MPS_MAM_BOM3
160,CH3683K1B09,"CAP CHIP 0.068UF 16V(+-10%,X7R 0402)",EMPTY,2,?,?,"PC1321,PC2161",?,?,?,?,NIC1_P3V3_BOM2
161,CH3683K1B09,"CAP CHIP 0.068UF 16V(+-10%,X7R 0402)",X7R,5,?,?,"PC2184,PC2185,PC2191,PC2226,PC2227",?,?,?,?,HSC1_BOM1
162,CH3683K1B09,"CAP CHIP 0.068UF 16V(+-10%,X7R 0402)",EMPTY,1,?,?,PC2201,?,?,?,?,E1S1_P3V3_BOM2
163,CH4101KEE01,"CAP CHIP 0.1UF 6.3V(10%,X6S,0201,H0.3)",X6S,6,?,?,"C1096,C1097,C2289,C2290,C2291,C2292",?,?,?,?,?
164,CH4104K1B00,"CAP CHIP 0.1U 25V(+-10%,X7R,0402)",X7R,251,?,?,"C174,C188,C204,C205,C206,C207,C210,C211,C537,C538,C539,C540,C543,C544,C548,C549,C552,C554,C559,C560,C561,C562,C567,C568,C569,C570,C578,C579,C580,C581,C592,C593,C607,C608,C609,C629,C639,C640,C641,C1122,C1150,C1173,C1175,C1233,C1234,C1235,C1236,C1237,C1238,C1239,C1240,C1274,C1275,C1278,C1279,C1282,C1283,C1288,C1292,C1305,C1317,C1320,C1321,C1322,C1323,C1325,C1337,C1592,C1613,C1614,C1619,C1647,C1663,C1664,C1707,C1713,C1751,C1766,C1769,C1770,C1775,C1796,C1797,C1803,C1809,C1810,C1817,C1818,C1819,C1820,C1821,C1822,C1823,C1824,C1825,C1826,C1827,C1831,C1832,C1833,C1834,C1835,C1836,C1837,C1838,C1839,C1840,C1841,C1859,C1860,C1861,C1862,C1873,C1874,C1875,C1876,C1877,C1878,C1879,C1880,C1882,C1886,C1889,C1905,C1906,C1907,C1923,C1924,C1925,C1941,C1942,C1943,C1944,C1945,C1946,C1947,C1957,C1958,C1963,C1977,C1979,C1997,C1998,C2010,C2012,C2013,C2014,C2015,C2017,C2018,C2019,C2020,C2021,C2022,C2024,C2027,C2056,C2067,C2069,C2071,C2249,C2252,C2253,C2254,C2257,C2258,C2259,C2274,C2275,C2276,C2283,C2285,C2286,C2329,C2330,C2333,C2334,C2335,C2336,C2337,C2338,C2339,C2341,C2344,C2345,C2346,C2347,C2348,C2360,C2376,C2377,C2378,C2394,C2444,PC221,PC330,PC386,PC390,PC474,PC548,PC577,PC624,PC628,PC1221,PC1224,PC1251,PC1254,PC1264,PC1267,PC1338,PC1339,PC1340,PC1341,PC1342,PC1343,PC1344,PC1345,PC1346,PC1347,PC1348,PC1349,PC1350,PC1351,PC1352,PC1354,PC1355,PC1356,PC1358,PC1359,PC1360,PC1361,PC1362,PC1363,PC1364,PC1365,PC1366,PC1367,PC1368,PC1369,PC1370,PC1371,PC1852,PC1853,PC1869,PC2091,PC2092,PC2137,PC2152,PC2217,PC2218,PC2238",?,?,?,?,?
165,CH4104K1B00,"CAP CHIP 0.1U 25V(+-10%,X7R,0402)",EMPTY,30,?,?,"C1324,C1708,C2293,C2294,C2295,C2296,C2297,C2314,C2315,C2318,C2319,C2320,C2321,C2324,C2325,C2370,C2371,C2392,C2393,PC214,PC329,PC334,PC467,PC547,PC2361,PC2362,PC2365,PC2366,PC2367,PC2368",?,?,?,?,?
166,CH4104K1B00,"CAP CHIP 0.1U 25V(+-10%,X7R,0402)",EMPTY,2,?,?,"C1347,C1757",?,?,?,?,ADC1_BOM1
167,CH4104K1B00,"CAP CHIP 0.1U 25V(+-10%,X7R,0402)",X7R,8,?,?,"C1863,C1864,C1865,C1866,C1868,C1869,C1870,C1871",?,?,?,?,PCIE REDRIVER1_BOM1
168,CH4104K1B00,"CAP CHIP 0.1U 25V(+-10%,X7R,0402)",X7R,5,?,?,"C2032,C2033,C2034,C2039,C2040",?,?,?,?,USB1_BOM1
169,CH4104K1B00,"CAP CHIP 0.1U 25V(+-10%,X7R,0402)",X7R,10,?,?,"C2046,C2047,C2048,C2049,C2050,C2051,C2052,C2177,C2178,C2194",?,?,?,?,ADC1_BOM2
170,CH4104K1B00,"CAP CHIP 0.1U 25V(+-10%,X7R,0402)",EMPTY,4,?,?,"C2351,C2352,C2353,C2354",?,?,?,?,PCIE REDRIVER1_BOM2
171,CH4104K1B00,"CAP CHIP 0.1U 25V(+-10%,X7R,0402)",X7R,2,?,?,"C2357,C2358",?,?,?,?,PCIE REDRIVER1_BOM2
172,CH4104K1B00,"CAP CHIP 0.1U 25V(+-10%,X7R,0402)",EMPTY,4,?,?,"C2363,C2364,C2458,PC1789",?,?,?,?,HSC1_BOM2
173,CH4104K1B00,"CAP CHIP 0.1U 25V(+-10%,X7R,0402)",EMPTY,3,?,?,"C5232,C5234,C5236",?,?,?,?,USB1_BOM2
174,CH4104K1B00,"CAP CHIP 0.1U 25V(+-10%,X7R,0402)",X7R,2,?,?,"PC2160,PC2174",?,?,?,NIC1_P12V_MPS_TIC_BOM4,NIC1_P12V_MPS_MAM_BOM3
175,CH4104K1B00,"CAP CHIP 0.1U 25V(+-10%,X7R,0402)",X7R,1,?,?,PC2206,?,?,?,E1S1_P12V_MPS_TIC_BOM4,E1S1_P12V_MPS_MAM_BOM3
176,CH4104K1B00,"CAP CHIP 0.1U 25V(+-10%,X7R,0402)",X7R,1,?,?,PC2241,?,?,?,?,SCM_P12V_BOM2
177,CH4106K1B01,"CAP CHIP 100NF 50V(+-10%,X7R,0402)",X7R,68,?,?,"C1042,C1172,C1227,C1332,C1339,C2179,C2449,C3271,PC178,PC181,PC193,PC194,PC199_P0_1,PC234,PC235,PC256,PC257,PC278,PC279,PC300,PC301,PC308_P0_1,PC376,PC379,PC401,PC402,PC431,PC434,PC446,PC447,PC452_P1_1,PC487,PC488,PC509,PC510,PC531,PC532,PC564,PC565,PC572_P1_1,PC606,PC607,PC612_P0_1,PC621_P1_1,PC636,PC639,PC1177,PC1178,PC1183_P0_4,PC1197,PC1198,PC1203_P1_4,PC1234,PC1236,PC1276,PC1284,PC1648,PC1649,PC1650,PC1651,PC1652,PC1653,PC1654,PC1655,PC1656,PC1657,PC1658,PC1659",?,?,?,?,?
178,CH4106K1B01,"CAP CHIP 100NF 50V(+-10%,X7R,0402)",EMPTY,17,?,?,"C2379,C2380,C2381,C2382,C2383,C2384,C2385,C2386,C2387,C2388,C2389,C2390,PC223,PC391,PC476,PC552,PC629",?,?,?,?,?
179,CH4106K1B01,"CAP CHIP 100NF 50V(+-10%,X7R,0402)",X7R,1,?,?,PC2156,?,?,?,NIC1_P12V_MPS_TIC_BOM4,NIC1_P12V_MPS_MAM_BOM3
180,CH4106K1B01,"CAP CHIP 100NF 50V(+-10%,X7R,0402)",X7R,1,?,?,PC2202,?,?,?,E1S1_P12V_MPS_TIC_BOM4,E1S1_P12V_MPS_MAM_BOM3
181,CH4106K1B01,"CAP CHIP 100NF 50V(+-10%,X7R,0402)",X7R,1,?,?,PC2235,?,?,?,?,SCM_P12V_BOM2
182,CH4221KEE00,"CAP CHIP 0.22UF 6.3V(+-10%,X6S,0201)",X6S,2,?,?,"C1436,C1437",?,?,?,?,?
183,CH4221MEE01,"CAP CHIP 0.22UF 6.3V(20%,X6S,0201)_DIFF BUS",X6S,374,TDK,C0603X6S0J224MT-A,"C139,C141,C142,C143,C144,C145,C146,C147,C148,C149,C150,C151,C152,C153,C154,C155,C156,C157,C158,C159,C160,C161,C162,C163,C164,C165,C166,C167,C168,C169,C170,C678,C679,C680,C681,C682,C683,C684,C685,C686,C687,C688,C689,C690,C691,C692,C693,C694,C695,C696,C697,C698,C699,C700,C701,C702,C703,C704,C705,C706,C707,C708,C709,C710,C711,C712,C713,C714,C715,C716,C717,C718,C719,C720,C721,C722,C723,C724,C725,C726,C727,C728,C729,C730,C731,C732,C733,C734,C735,C736,C737,C738,C739,C740,C741,C742,C743,C744,C745,C746,C747,C748,C749,C750,C751,C752,C753,C754,C755,C756,C757,C758,C759,C760,C761,C762,C763,C764,C765,C766,C767,C768,C769,C770,C771,C772,C773,C806,C807,C808,C809,C810,C811,C812,C813,C814,C815,C816,C817,C818,C819,C820,C821,C822,C823,C824,C825,C826,C827,C828,C829,C830,C831,C832,C833,C834,C835,C836,C837,C838,C839,C840,C841,C842,C843,C844,C845,C846,C847,C848,C849,C850,C851,C852,C853,C854,C855,C856,C857,C858,C859,C860,C861,C862,C863,C864,C865,C866,C867,C868,C869,C870,C871,C872,C873,C874,C875,C876,C877,C878,C879,C880,C881,C882,C883,C884,C885,C886,C887,C888,C889,C890,C891,C892,C893,C894,C895,C896,C897,C898,C899,C900,C901,C902,C903,C904,C905,C906,C907,C908,C909,C910,C911,C912,C913,C914,C915,C916,C917,C918,C919,C920,C921,C922,C923,C924,C925,C926,C927,C928,C929,C930,C931,C932,C933,C934,C935,C936,C937,C938,C939,C940,C941,C942,C943,C944,C945,C946,C947,C948,C949,C950,C951,C952,C953,C954,C955,C956,C957,C958,C959,C960,C961,C962,C963,C964,C965,C1098,C1099,C1100,C1101,C1102,C1103,C1104,C1105,C1516,C1517,C1518,C1519,C1520,C1521,C1522,C1523,C1524,C1525,C1526,C1527,C1528,C1529,C1530,C1531,C1532,C1533,C1534,C1535,C1536,C1537,C1538,C1539,C1540,C1541,C1542,C1543,C1544,C1545,C1546,C1547,C1548,C1549,C1550,C1552,C1553,C1554,C1555,C1556,C1557,C1558,C1559,C1560,C1563,C1564,C1565,C1566,C1567,C1568,C1569,C1570,C1571,C1572,C1573,C1574,C1575,C1576,C1577,C1578,C1579,C1791,C1792,C1793,C1794,C1989,C1990,C1991,C1992,C1993,C1994,C1995,C1996,C2073,C2074,C2075,C2076,C2077,C2078",?,?,?,?,?
184,CH4223K1B00,"CAP CHIP 0.22U 16V(10%,X7R,0402)",X7R,2,?,?,"PC2153,PC2164",?,Comp-Approve,End of Design,NIC1_P12V_MPS_TIC_BOM4,NIC1_P12V_MPS_MAM_BOM3
185,CH4223K1B00,"CAP CHIP 0.22U 16V(10%,X7R,0402)",X7R,1,?,?,PC2196,?,Comp-Approve,End of Design,E1S1_P12V_MPS_TIC_BOM4,E1S1_P12V_MPS_MAM_BOM3
186,CH4223K1B00,"CAP CHIP 0.22U 16V(10%,X7R,0402)",X7R,1,?,?,PC2229,?,Comp-Approve,End of Design,?,SCM_P12V_BOM2
187,CH4224K1B01,"CAP CHIP 0.22U 25V(10%,X7R,0402)",X7R,11,?,?,"C1226,C2359,C2541,PC568,PC1222,PC1235,PC1252,PC1265,PC1275,PC1283,PC1847",?,Comp-Release Qty,End of Design,?,?
188,CH4331KEB01,"CAP CHIP 0.33UF 6.3V(10%,X6S,0402)_FOR DIFF BUS",X6S,2,MUR,GRM155C80J334K,"C2349,C2350",?,Comp-Approve,End of Design,?,?
189,CH5101K1B01,"CAP CHIP 1U,6.3V(+-10%,X7R,0402)",EMPTY,6,?,?,"C1250,C1253,C1256,C1257,C1264,C1265",?,?,?,?,?
190,CH5103KEB01,"CAP CHIP 1UF 16V(10%,X6S,0402)",X6S,62,?,?,"PC177,PC191_P0_1,PC192_P0_2,PC225,PC232_P0_8,PC233_P0_7,PC242_P0_8,PC243_P0_7,PC254_P0_6,PC255_P0_5,PC276_P0_4,PC277_P0_3,PC298_P0_2,PC299_P0_1,PC310_P0_1,PC337,PC375,PC394,PC399_P1_1,PC400_P1_2,PC408_P1_2,PC430,PC444_P1_1,PC445_P1_2,PC478,PC485_P1_8,PC486_P1_7,PC495_P1_8,PC496_P1_7,PC507_P1_6,PC508_P1_5,PC529_P1_4,PC530_P1_3,PC555,PC562_P1_2,PC563_P1_1,PC574_P1_1,PC604_P0_1,PC605_P0_2,PC613_P0_2,PC632,PC635,PC813,PC814,PC1173,PC1175_P0_3,PC1176_P0_4,PC1183_P0_3,PC1193,PC1194,PC1195_P1_3,PC1196,PC1196_P1_4,PC1204_P1_3,PC1219,PC1249,PC1262,PC1274,PC1282,PC1289,PC1372,PC1846",?,?,?,?,?
191,CH5104KEB02,"CAP CHIP 1UF 25V(+-10%,X6S,0402)",X6S,42,?,?,"C107,C541,C542,C545,C546,C547,C550,C551,C605,C606,C610,C611,C1177,C1289,C1290,C1291,C1293,C1311,C1312,C1315,C1319,C1561,C1612,C1884,C2007,C2243,C2246,C2247,C2248,PC113,PC644,PC1642,PC1848,PC2079,PC2139,PC2140,PC2207,PC2221,PC2222,PC2230,PC2643,PC5328",?,?,?,?,?
192,CH5104KEB02,"CAP CHIP 1UF 25V(+-10%,X6S,0402)",EMPTY,16,?,?,"C613,C614,C615,C616,C621,C622,C623,C624,C1318,C1562,C2316,C2317,C2322,C2323,C2369,C4562",?,?,?,?,?
193,CH5104KEB02,"CAP CHIP 1UF 25V(+-10%,X6S,0402)",X6S,3,?,?,"C2031,C2035,C2041",?,?,?,?,USB1_BOM1
194,CH5104KEB02,"CAP CHIP 1UF 25V(+-10%,X6S,0402)",X6S,1,?,?,C2355,?,?,?,?,PCIE REDRIVER1_BOM2
195,CH5104KEB02,"CAP CHIP 1UF 25V(+-10%,X6S,0402)",EMPTY,1,?,?,C5229,?,?,?,?,USB1_BOM2
196,CH5104KEB02,"CAP CHIP 1UF 25V(+-10%,X6S,0402)",X6S,8,?,?,"PC1525,PC2103,PC2181,PC2186,PC2187,PC2188,PC2223,PC3272",?,?,?,?,HSC1_BOM1
197,CH5104KEB02,"CAP CHIP 1UF 25V(+-10%,X6S,0402)",X6S,4,?,?,"PC190,PC2086,PC2093,PC2147",?,?,?,?,NIC1_P3V3_BOM1
198,CH5104KEB02,"CAP CHIP 1UF 25V(+-10%,X6S,0402)",EMPTY,4,?,?,"PC2085,PC2087,PC2098,PC2146",?,?,?,NIC1_P12V_MAM_TIC_BOM2,NIC1_P12V_MAM_MAM_BOM1
199,CH5104KEB02,"CAP CHIP 1UF 25V(+-10%,X6S,0402)",X6S,2,?,?,"PC2154,PC2165",?,?,?,NIC1_P12V_MPS_TIC_BOM4,NIC1_P12V_MPS_MAM_BOM3
200,CH5104KEB02,"CAP CHIP 1UF 25V(+-10%,X6S,0402)",EMPTY,2,?,?,"PC2159,PC2169",?,?,?,?,NIC1_P3V3_BOM2
201,CH5104KEB02,"CAP CHIP 1UF 25V(+-10%,X6S,0402)",X6S,1,?,?,PC2198,?,?,?,E1S1_P12V_MPS_TIC_BOM4,E1S1_P12V_MPS_MAM_BOM3
202,CH5104KEB02,"CAP CHIP 1UF 25V(+-10%,X6S,0402)",EMPTY,1,?,?,PC2200,?,?,?,?,E1S1_P3V3_BOM2
203,CH5104KEB02,"CAP CHIP 1UF 25V(+-10%,X6S,0402)",X6S,3,?,?,"PC2208,PC2210,PC2212",?,?,?,?,E1S1_P3V3_BOM1
204,CH5104KEB02,"CAP CHIP 1UF 25V(+-10%,X6S,0402)",EMPTY,2,?,?,"PC2209,PC2211",?,?,?,E1S1_P12V_MAM_TIC_BOM2,E1S1_P12V_MAM_MAM_BOM1
205,CH5104KEB02,"CAP CHIP 1UF 25V(+-10%,X6S,0402)",X6S,1,?,?,PC2231,?,?,?,?,SCM_P12V_BOM2
206,CH5104KEB02,"CAP CHIP 1UF 25V(+-10%,X6S,0402)",EMPTY,2,?,?,"PC2233,PC2234",?,?,?,?,SCM_P12V_BOM1
207,CH5221MEB00,"CAP CHIP 2.2U 6.3V(+-20%,X6S,0402)",X6S,32,?,?,"C2,C5,C8,C11,C14,C17,C20,C23,C26,C29,C32,C35,C38,C41,C44,C47,C50,C53,C56,C59,C62,C65,C68,C72,C75,C78,C81,C84,C87,C90,C93,C96",?,?,?,?,?
208,CH5222KEB01,"CAP CHIP 2.2UF 10V(+-10%,X6S,0402)",X6S,68,?,?,"C1183,C1189,C1200,C1204,C1214,C1242,PC175,PC187,PC188,PC226,PC227,PC228_P0_8,PC229_P0_7,PC248,PC249,PC250_P0_6,PC251_P0_5,PC270,PC271,PC272_P0_4,PC273_P0_3,PC292,PC293,PC294_P0_2,PC295_P0_1,PC373,PC395,PC396,PC428,PC440,PC441,PC479,PC480,PC481_P1_8,PC482_P1_7,PC501,PC502,PC503_P1_6,PC504_P1_5,PC523,PC524,PC525_P1_4,PC526_P1_3,PC556,PC557,PC558_P1_2,PC559_P1_1,PC600,PC601,PC633,PC1171,PC1172,PC1191,PC1192,PC1211_P0_1,PC1212_P0_2,PC1213_P0_3,PC1214_P0_4,PC1242_P1_1,PC1243_P1_2,PC1244_P1_3,PC1245_P1_4,PC2946,PC2947,PC2948,PC2949,PC2950,PC2951",?,?,?,?,?
209,CH5223KE901,"CAP CHIP 2.2U 16V(+-10%,X6S,0603)",X6S,1,?,?,PC591,?,?,?,?,?
210,CH5223M1900,"CAP CHIP 2.2UF 16V(20%,X7R,0603)",X7R,2,?,?,"PC1320,PC2158",?,?,?,NIC1_P12V_MPS_TIC_BOM4,NIC1_P12V_MPS_MAM_BOM3
211,CH5223M1900,"CAP CHIP 2.2UF 16V(20%,X7R,0603)",X7R,1,?,?,PC2205,?,?,?,E1S1_P12V_MPS_TIC_BOM4,E1S1_P12V_MPS_MAM_BOM3
212,CH5223M1900,"CAP CHIP 2.2UF 16V(20%,X7R,0603)",X7R,1,?,?,PC2239,?,?,?,?,SCM_P12V_BOM2
213,CH5473KE902,"CAP CHIP 4.7UF 16V(+-10%,X6S,0603)",X6S,2,?,?,"PC8,PC581",?,?,?,?,?
214,CH6101ME900,"CAP CHIP 10U 6.3V(+-20%,X6S,0603)",X6S,18,?,?,"C108,C172,C208,C209,C1251,C1252,C1254,C1255,C1260,C1261,C1309,C1310,C1313,C1314,C1409,C2328,C2331,C2332",?,Comp-Approve,End of Design,?,?
215,CH6101MEB01,"CAP CHIP 10UF 6.3V(+-20%,X6S,0402)",X6S,19,?,?,"C1,C71,C1203,C1205,C1206,C1207,C1210,C1228,C1231,C1262,C1263,C1266,C1842,C1935,C1936,C1937,C1938,C1939,C1940",?,?,?,?,?
216,CH6101MEB01,"CAP CHIP 10UF 6.3V(+-20%,X6S,0402)",X6S,1,?,?,C2038,?,?,?,?,USB1_BOM1
217,CH6101MEB01,"CAP CHIP 10UF 6.3V(+-20%,X6S,0402)",EMPTY,1,?,?,C2313,?,?,?,?,?
218,CH6101MEB03,"CAP CHIP 10UF 6.3V(+-20%,X6S,0402)MUR",X6S,88,?,?,"C221,C222,C223,C224,C226,C227,C228,C229,C231,C232,C233,C234,C236,C237,C238,C239,C241,C242,C243,C244,C246,C247,C248,C249,C251,C252,C253,C254,C256,C257,C258,C259,C261,C262,C263,C264,C266,C267,C268,C269,C966,C967,C968,C969,C970,C971,C972,C973,C974,C975,C976,C977,C978,C979,C980,C981,C982,C983,C984,C985,C986,C987,C988,C989,C990,C991,C992,C993,C994,C995,C996,C997,C998,C999,C1000,C1001,C1002,C1003,C1004,C1005,C1336,C2443,PC224,PC335,PC392,PC477,PC553,PC630",?,?,?,?,?
219,CH6103KEA00,"CAP CHIP 10UF 16V(+-10%,X6S,0805)",X6S,68,?,?,"C3,C4,C6,C7,C9,C10,C12,C13,C15,C16,C18,C19,C21,C22,C24,C25,C27,C28,C30,C31,C33,C34,C36,C37,C39,C40,C42,C43,C45,C46,C48,C49,C51,C52,C54,C55,C57,C58,C60,C61,C63,C64,C66,C67,C69,C70,C73,C74,C76,C77,C79,C80,C82,C83,C85,C86,C88,C89,C91,C92,C94,C95,C97,C98,C1170,C1331,C1333,C1340",?,?,?,?,?
220,CH6103KEA00,"CAP CHIP 10UF 16V(+-10%,X6S,0805)",EMPTY,2,?,?,"C1171,C1338",?,?,?,?,?
221,CH6103KEA00,"CAP CHIP 10UF 16V(+-10%,X6S,0805)",EMPTY,2,?,?,"C1767,C1768",?,?,?,?,ADC1_BOM1
222,CH6103KEA00,"CAP CHIP 10UF 16V(+-10%,X6S,0805)",X6S,1,?,?,C2356,?,?,?,?,PCIE REDRIVER1_BOM2
223,CH6103KEA01,"CAP CHIP 10UF 16V(+-10%,X6S,0805)MUR",X6S,5,?,?,"PC1232,PC1233,PC2081,PC2142,PC2220",?,?,?,?,?
224,CH6103KEA01,"CAP CHIP 10UF 16V(+-10%,X6S,0805)MUR",EMPTY,2,?,?,"PC2163,PC2173",?,?,?,?,NIC1_P3V3_BOM2
225,CH6103KEA01,"CAP CHIP 10UF 16V(+-10%,X6S,0805)MUR",EMPTY,1,?,?,PC2204,?,?,?,?,E1S1_P3V3_BOM2
226,CH6103KEA03,"CAP CHIP 10UF 16V(+-10%,X6S,0805)SAM",X6S,5,?,?,"PC2082,PC2143,PC2219,PC2240,PC2280",?,?,?,?,?
227,CH6104KEA00,"CAP CHIP 10U 25V(+-10%,X6S,0805,H1.25)",X6S,1,?,?,C1867,?,?,?,?,PCIE REDRIVER1_BOM1
228,CH6104KEA00,"CAP CHIP 10U 25V(+-10%,X6S,0805,H1.25)",X6S,2,?,?,"C563,C1883",?,?,?,?,?
229,CH610KME907,"CAP CHIP 10U 4V(+-20%,X6S,0603)AEC",EMPTY,2,?,?,"C2448,C3270",?,?,?,?,?
230,CH6221ME900,"CAP CHIP 22U 6.3V(+-20%,X6S,0603)",X6S,6,?,?,"C1184,C1191,C1201,C1920,C1921,C1922",?,?,?,?,?
231,CH6222MEA01,"CAP CHIP 22U 10V(+-20%,X6S,0805)MUR",X6S,5,?,?,"PC1599,PC1600,PC1855,PC1856,PC1868",?,?,?,?,?
232,CH6223MEA00,"CAP CHIP 22U 16V(+-20%,X6S,0805)",X6S,5,?,?,"C1213,C1232,C1829,C1830,C2284",?,?,?,?,?
233,CH6223MEA01,"CAP CHIP 22UF 16V(+-20%,X6S,0805)MUR",X6S,136,?,?,"C513,C535,C1276,C1277,PC71,PC179,PC180,PC195_P0_1,PC196_P0_2,PC197_P0_1,PC198_P0_2,PC236_P0_8,PC237_P0_7,PC238_P0_8,PC239_P0_7,PC240_P0_8,PC241_P0_7,PC258_P0_6,PC259_P0_5,PC260_P0_6,PC261_P0_5,PC262_P0_6,PC263_P0_5,PC280_P0_4,PC281_P0_3,PC282_P0_4,PC283_P0_3,PC284_P0_4,PC285_P0_3,PC302_P0_2,PC303_P0_1,PC304_P0_2,PC305_P0_1,PC306_P0_2,PC307_P0_1,PC377,PC378,PC403_P1_1,PC404_P1_2,PC405_P1_1,PC406_P1_2,PC432,PC433,PC448_P1_1,PC449_P1_2,PC450_P1_1,PC451_P1_2,PC489_P1_8,PC490_P1_7,PC491_P1_8,PC492_P1_7,PC493_P1_8,PC494_P1_7,PC511_P1_6,PC512_P1_5,PC513_P1_6,PC514_P1_5,PC515_P1_6,PC516_P1_5,PC533_P1_4,PC534_P1_3,PC535_P1_4,PC536_P1_3,PC537_P1_4,PC538_P1_3,PC566_P1_2,PC567,PC567_P1_1,PC568_P1_2,PC569_P1_1,PC570,PC570_P1_2,PC571,PC571_P1_1,PC576,PC608_P0_1,PC609_P0_2,PC610_P0_1,PC611_P0_2,PC637,PC638,PC720_P0_1,PC721_P0_2,PC722_P0_3,PC723_P0_4,PC724_P1_1,PC725_P1_2,PC726_P1_3,PC727_P1_4,PC831,PC1179_P0_3,PC1180_P0_4,PC1181_P0_3,PC1182_P0_4,PC1199_P1_3,PC1200_P1_4,PC1201_P1_3,PC1202_P1_4,PC1216,PC1217,PC1218,PC1247,PC1248,PC1259,PC1260,PC1261,PC1272,PC1273,PC1280,PC1281,PC1669,PC1670,PC1671,PC1672,PC1673,PC1674,PC1675,PC1676,PC1677,PC1678,PC1679,PC1680,PC1681,PC1682,PC1683,PC1684,PC1849,PC1850,PC1898,PC2260,PC2261,PC2262,PC2263,PC2342,PC2343,PC2344",?,?,?,?,?
234,CH6223MEA03,"CAP CHIP 22U 16V(20%,X6S,0805)SAM",X6S,3,?,?,"PC2080,PC2141,PC2242",?,?,?,?,?
235,CH622KME901,"CAP CHIP 22UF 4V(+-20%,X6S,0603)",X6S,10,?,?,"C1178,C1181,C1182,C1185,C1186,C1187,C1192,C1197,C1198,C1202",?,?,?,?,?
236,CH622KMEA03,"CAP CHIP 22U 4V(+-20%,X6S,0805)MUR",X6S,85,?,?,"PC1,PC2,PC184,PC186,PC202_P0_1,PC203_P0_2,PC204_P0_1,PC205_P0_2,PC244_P0_8,PC245_P0_7,PC246_P0_8,PC247_P0_7,PC266_P0_6,PC267_P0_5,PC268_P0_6,PC269_P0_5,PC288_P0_4,PC289_P0_3,PC290_P0_4,PC291_P0_3,PC311_P0_2,PC312_P0_1,PC313_P0_2,PC314_P0_1,PC381,PC382,PC410_P1_1,PC411_P1_2,PC412_P1_1,PC413_P1_2,PC435,PC437,PC455_P1_1,PC456_P1_2,PC457_P1_1,PC458_P1_2,PC497_P1_8,PC498_P1_7,PC499_P1_8,PC500_P1_7,PC519_P1_6,PC520_P1_5,PC521_P1_6,PC522_P1_5,PC541_P1_4,PC542_P1_3,PC543_P1_4,PC544_P1_3,PC575_P1_2,PC576_P1_1,PC577_P1_2,PC578_P1_1,PC615_P0_1,PC616_P0_2,PC617_P0_1,PC618_P0_2,PC641,PC642,PC1185_P0_3,PC1186_P0_4,PC1187_P0_3,PC1188_P0_4,PC1206,PC1206_P1_3,PC1207,PC1207_P1_4,PC1208_P1_3,PC1209_P1_4,PC1237,PC1238,PC1239,PC1240,PC1241,PC1255,PC1256,PC1257,PC1268,PC1269,PC1270,PC1277,PC1278,PC1279,PC1285,PC1286,PC1287",?,?,?,?,?
237,CH622KMEB01,"CAP CHIP 22UF 4V(+-20%,X6S,0402)MUR",X6S,137,?,?,"C271,C272,C273,C274,C275,C276,C277,C278,C279,C280,C281,C282,C283,C284,C285,C286,C287,C288,C289,C290,C291,C292,C293,C294,C295,C296,C297,C298,C299,C300,C301,C302,C303,C304,C305,C306,C307,C308,C309,C310,C399,C400,C401,C402,C403,C404,C405,C406,C407,C408,C409,C410,C411,C412,C413,C414,C415,C416,C417,C418,C419,C420,C421,C422,C423,C424,C425,C426,C427,C428,C429,C430,C431,C432,C433,C434,C435,C436,C437,C438,C439,C440,C441,C442,C443,C444,C445,C446,C490,C534,C590,C1006,C1007,C1008,C1009,C1010,C1011,C1012,C1013,C1014,C1015,C1016,C1017,C1018,C1019,C1020,C1021,C1022,C1023,C1024,C1025,C1026,C1027,C1028,C1029,C1030,C1031,C1032,C1033,C1034,C1035,C1036,C1037,C1038,C1039,C1040,C1041,C1043,C1044,C1045,C1302,C1353,C1362,C1363,C1364,C1365,C1366",?,?,?,?,?
238,CH6471MEA02,"CAP CHIP 47U 6.3V(+-20%,X6S,0805)",X6S,2,?,?,"C1243,C1245",?,?,?,?,?
239,CH647KMEA04,"CAP CHIP 47U 4V(+-20%,X6S,0805)MUR",X6S,195,?,?,"C101,C212,C213,C214,C215,C216,C217,C218,C219,C220,C225,C230,C235,C240,C245,C250,C255,C260,C265,C270,C311,C312,C313,C314,C315,C316,C317,C318,C320,C321,C322,C323,C324,C325,C326,C327,C328,C329,C330,C332,C333,C335,C336,C337,C338,C339,C341,C342,C343,C344,C345,C346,C347,C348,C349,C350,C351,C352,C353,C354,C355,C356,C357,C358,C359,C360,C361,C362,C363,C364,C365,C366,C367,C368,C369,C370,C371,C372,C373,C374,C376,C377,C379,C380,C381,C382,C383,C385,C386,C387,C388,C389,C390,C391,C392,C393,C394,C395,C396,C397,C398,C447,C448,C449,C450,C451,C452,C453,C454,C455,C456,C457,C458,C459,C460,C461,C462,C463,C464,C466,C467,C468,C470,C471,C473,C474,C476,C477,C478,C479,C481,C482,C483,C484,C485,C486,C487,C491,C492,C493,C494,C495,C496,C497,C498,C499,C500,C501,C502,C503,C504,C505,C506,C507,C508,C510,C511,C512,C514,C515,C517,C518,C520,C521,C522,C523,C525,C526,C527,C528,C529,C530,C531,C1244,C1246,C1247,C1248,C1249,C1258,C1259,C1272,C1273,C1387,C1388,C1390,C1392,C1396,C1397,C1398,C1399,C1400,C1403,C1404,PC1225,PC1226",?,?,?,?,?
240,CH647LME900,"CAP CHIP 47U 2.5V(+-20%,X6S,0603)MUR",X6S,16,?,?,"C465,C472,C475,C488,C489,C509,C516,C519,C532,C533,C1389,C1391,C1393,C1405,C1406,C1407",?,Comp-Approve,End of Design,?,?
241,CH733LY8802,"CAPCHIP 330U 2.5V(10/-35%,SPCAP,7343)MAT",SPCAP,10,?,?,"PC418,PC623,PC1187,PC1205,PC1900,PC1930,PC2170,PC2171,PC2172,PC2645",?,?,?,?,?
242,CH733LY8802,"CAPCHIP 330U 2.5V(10/-35%,SPCAP,7343)MAT",EMPTY,8,?,?,"PC189,PC323,PC326,PC587,PC590,PC1920,PC1990,PC2336",?,?,?,?,?
243,CH733RY8807,"CAP CHIP 330U 2V(+10-35%,SPCAP,7343)MAT",SPCAP,8,?,?,"PC117,PC1229,PC1573,PC1575,PC1588,PC1594,PC1910,PC1940",?,?,?,?,?
244,CS+001DFR10,RES CHIP 0.001 3W +-1%(2512)RLC_4P,CHIP,2,RLC,LR2512-23R001F4,"R1837,R1838",?,?,?,?,?
245,CS+003DFR03,RES CHIP 0.003 3W +-1%(2512)RLC_4P,EMPTY,1,RLC,LR2512-23R003F4,PR3,?,?,?,?,HSC1_BOM2
246,CS+0108F128,RES CHIP 0.01 1W +-1%(2512),CHIP,5,?,?,"R3633,R3634,R3635,R3645,R3767",?,Comp-Release Qty,End of Design,?,?
247,CS+0308BR00,0.03ohm 2512,EMPTY,2,?,?,"PR2554,PR2556",?,?,?,?,?
248,CS-1002FB04,RES CHIP 1 1/16W +-1%(0402)EF,CHIP,8,?,?,"PR130,PR176,PR220,PR283,PR323,PR375,PR389,R4077",?,Comp-Approve,End of Design,?,?
249,CS-1002FB04,RES CHIP 1 1/16W +-1%(0402)EF,EMPTY,8,?,?,"PR2510,PR2511,PR2512,PR2513,PR2520,PR2521,PR2522,PR2523",?,Comp-Approve,End of Design,?,HSC1_BOM2
250,CS-1003F900,RES CHIP 1 1/10W +-1%(0603)EF,CHIP,12,?,?,"R442,R447,R519,R3344,R3345,R3346,R3347,R3348,R3349,R3458,R4475,R4493",?,Comp-Approve,End of Design,?,?
251,CS-2202FB01,RES CHIP 2.2 1/16W +-1%(0402)EF,CHIP,32,?,?,"PR97,PR101,PR102,PR134,PR135,PR140,PR141,PR146,PR147,PR152,PR153,PR200,PR226,PR227,PR250,PR254,PR255,PR287,PR288,PR293,PR294,PR299,PR300,PR327,PR328,PR355,PR356,PR380,PR1299,PR1300,PR1306,PR1307",?,Comp-Approve,End of Design,?,?
252,CS-2203F902,RES CHIP 2.2 1/10W +-1%(0603)EF,CHIP,2,?,?,"R571,R572",?,Comp-Approve,End of Design,?,?
253,CS-3302FB01,RES CHIP 3.3 1/16W +-1%(0402)EF,CHIP,32,?,?,"PR1766,PR1767,PR1768,PR1769,PR1770,PR1771,PR1772,PR1773,PR1774,PR1775,PR1778,PR1780,PR1781,PR1782,PR1783,PR1784,PR1786,PR1787,PR1788,PR1789,PR1790,PR1791,PR1792,PR1793,PR1794,PR1795,PR1798,PR1800,PR1801,PR1802,PR1803,PR1804",?,Comp-Approve,End of Design,?,?
254,CS-5102JB02,RES CHIP 5.1 1/16W +-5%(0402)EF,CHIP,1,?,?,PR1329,?,?,?,?,?
255,CS00002JB13,RES CHIP 0 1/16W +-5%(0402)EF,CHIP,519,?,?,"PR1,PR2,PR108,PR120,PR121,PR136,PR137,PR142,PR143,PR148,PR149,PR154,PR155,PR156,PR158,PR170,PR171,PR216,PR242,PR261,PR273,PR274,PR275,PR289,PR290,PR295,PR296,PR301,PR302,PR303,PR305,PR317,PR329,PR330,PR338,PR345,PR371,PR395,PR402,PR442,PR444,PR447,PR639,PR678,PR701,PR702,PR832,PR835,PR1311,PR1315,PR1322,PR1323,PR1324,PR1325,PR1326,PR1331,PR1332,PR1333,PR1334,PR1335,PR1338,PR1776,PR1777,PR1779,PR1785,PR1796,PR1797,PR1799,PR1805,PR3002,PR3337,PR3338,PR3339,PR4220,PR4221,PR4222,PR4223,PR4224,PR4225,PR4230,PR4231,PR4232,PR4233,PR4234,PR4235,PR4236,PR4242,PR4243,PR4244,PR4245,PR4246,PR4251,PR4252,PR4253,PR4254,PR4255,PR4256,PR4257,PR4271,PR4272,PR4683,PR4699,R12,R13,R15,R16,R20,R21,R55,R56,R58,R59,R122,R124,R126,R128,R130,R132,R142,R144,R149,R160,R162,R164,R166,R168,R171,R188,R208,R210,R239,R240,R297,R299,R302,R304,R308,R309,R311,R312,R336,R337,R338,R340,R341,R342,R344,R345,R346,R362,R363,R365,R416,R417,R418,R429,R444,R445,R480,R481,R482,R483,R486,R506,R553,R554,R593,R594,R595,R596,R597,R598,R599,R600,R670,R672,R674,R676,R687,R689,R691,R693,R700,R737,R738,R746,R762,R764,R765,R815,R816,R817,R818,R835,R836,R837,R838,R851,R852,R853,R854,R859,R860,R861,R915,R916,R917,R918,R998,R999,R1010,R1011,R1012,R1014,R1016,R1018,R1020,R1021,R1022,R1023,R1139,R1147,R1148,R1184,R1214,R1240,R1247,R1249,R1294,R1295,R1296,R1297,R1318,R1345,R1348,R1349,R1389,R1461,R1463,R1464,R1525,R1543,R1547,R1640,R1650,R1652,R1671,R1680,R1721,R1724,R1744,R1748,R1798,R1801,R1815,R1816,R1821,R1853,R1944,R1950,R1959,R1960,R2114,R2155,R2208,R2209,R2210,R2211,R2255,R2268,R2313,R2316,R2347,R2348,R2350,R2358,R2360,R2366,R2369,R2370,R2376,R2379,R2380,R2387,R2388,R2389,R2390,R2391,R2394,R2397,R2400,R2401,R2402,R2403,R2405,R2408,R2412,R2413,R2414,R2415,R2416,R2452,R2513,R2520,R2521,R2523,R2526,R2529,R2531,R2550,R2552,R2557,R2558,R2560,R2561,R2562,R2563,R2565,R2566,R2570,R2572,R2574,R2576,R2577,R2579,R2580,R2582,R2591,R2594,R2595,R2597,R2659,R2660,R2676,R2703,R2704,R2706,R2707,R2725,R2792,R2802,R2803,R2848,R2899,R2905,R2906,R2922,R2967,R2968,R2969,R2971,R2982,R2983,R2992,R2994,R3023,R3033,R3045,R3046,R3047,R3048,R3049,R3051,R3066,R3067,R3103,R3105,R3106,R3107,R3108,R3109,R3110,R3111,R3123,R3124,R3125,R3126,R3142,R3143,R3168,R3169,R3170,R3171,R3172,R3177,R3178,R3233,R3236,R3237,R3244,R3263,R3264,R3294,R3303,R3304,R3305,R3306,R3307,R3308,R3326,R3327,R3335,R3336,R3337,R3338,R3352,R3353,R3354,R3355,R3393,R3394,R3441,R3442,R3443,R3499,R3516,R3517,R3518,R3526,R3527,R3559,R3560,R3561,R3563,R3580,R3581,R3620,R3636,R3637,R3710,R3713,R3714,R3715,R3716,R3717,R3718,R3719,R3720,R3721,R3722,R3751,R3752,R3770,R3772,R3775,R3776,R3777,R3778,R3779,R3924,R3996,R4056,R4060,R4064,R4075,R4076,R4088,R4177,R4212,R4213,R4214,R4215,R4216,R4268,R4305,R4306,R4460,R4461,R4467,R4468,R4473,R4474,R4501,R4503,R4504,R4511,R4513,R4531,R4534,R4593,R4594,R4595,R4599,R4600,R4601,R4602,R4606,R4607,R4624,R4626,R4627,R4628,R4629,R4630,R4631,R4632,R4633,R4695,R4696,R4697,R4720,R4721,R4728,R4729,R4734,R4735,R4736,R4741,R4742,R4752,R4753,R4780,R4781,R4802,R4803,R5234,R5236,R5377,R5487",?,Comp-Approve,End of Design,?,?
256,CS00002JB13,RES CHIP 0 1/16W +-5%(0402)EF,EMPTY,100,?,?,"PR107,PR157,PR260,PR304,PR396,PR403,PR409,PR410,PR443,PR632,PR633,PR640,PR699,PR703,PR704,PR4217,PR4218,PR4227,PR4228,PR4238,PR4239,PR4248,PR4249,PR4698,PR4700,R448,R665,R666,R667,R668,R682,R683,R684,R685,R1013,R1015,R1017,R1019,R1607,R1648,R1695,R1720,R1745,R1831,R1832,R1833,R1839,R1840,R2071,R2132,R2256,R2257,R2330,R2474,R2705,R2724,R2800,R2801,R2893,R2894,R2986,R2987,R3064,R3206,R3213,R3214,R3215,R3254,R3302,R3440,R3472,R4083,R4084,R4450,R4454,R4455,R4462,R4466,R4471,R4472,R4569,R4570,R4571,R4572,R4573,R4574,R4575,R4576,R4577,R4578,R4613,R4615,R4652,R4673,R4717,R4748,R4749,R4757,R4758,R4807",?,Comp-Approve,End of Design,?,?
257,CS00002JB13,RES CHIP 0 1/16W +-5%(0402)EF,CHIP,21,?,?,"PR2149,PR3910,PR3911,PR3916,PR3917,PR3919,PR3920,PR3921,PR3922,PR3928,PR3930,PR3980,PR3981,PR3988,PR3989,PR3992,PR3993,PR3994,PR3995,R1714,R2586",?,Comp-Approve,End of Design,?,HSC1_BOM1
258,CS00002JB13,RES CHIP 0 1/16W +-5%(0402)EF,EMPTY,4,?,?,"PR4012,R3997,R4062,R4708",?,Comp-Approve,End of Design,?,SCM_P12V_BOM1
259,CS00002JB13,RES CHIP 0 1/16W +-5%(0402)EF,EMPTY,7,?,?,"R1792,R1793,R3679,R3681,R3683,R3685,R3687",?,Comp-Approve,End of Design,?,ADC1_BOM1
260,CS00002JB13,RES CHIP 0 1/16W +-5%(0402)EF,CHIP,7,?,?,"R2786,R2787,R3651,R3652,R3655,R3662,R3666",?,Comp-Approve,End of Design,?,USB1_BOM1
261,CS00002JB13,RES CHIP 0 1/16W +-5%(0402)EF,EMPTY,4,?,?,"R2788,R2789,R2790,R2791",?,Comp-Approve,End of Design,?,USB1_BOM2
262,CS00002JB13,RES CHIP 0 1/16W +-5%(0402)EF,EMPTY,6,?,?,"R3144,R3784,R3827,R3831,R4059,R4061",?,Comp-Approve,End of Design,NIC1_P12V_MAM_TIC_BOM2,NIC1_P12V_MAM_MAM_BOM1
263,CS00002JB13,RES CHIP 0 1/16W +-5%(0402)EF,CHIP,2,?,?,"R3630,R3834",?,Comp-Approve,End of Design,NIC1_P12V_MPS_TIC_BOM4,NIC1_P12V_MPS_MAM_BOM3
264,CS00002JB13,RES CHIP 0 1/16W +-5%(0402)EF,EMPTY,2,?,?,"R3631,R3845",?,Comp-Approve,End of Design,?,NIC1_P3V3_BOM2
265,CS00002JB13,RES CHIP 0 1/16W +-5%(0402)EF,CHIP,7,?,?,"R3671,R3672,R3680,R3682,R3684,R3686,R3688",?,Comp-Approve,End of Design,?,ADC1_BOM2
266,CS00002JB13,RES CHIP 0 1/16W +-5%(0402)EF,CHIP,4,?,?,"R3785,R3794,R3807,R3832",?,Comp-Approve,End of Design,?,NIC1_P3V3_BOM1
267,CS00002JB13,RES CHIP 0 1/16W +-5%(0402)EF,EMPTY,1,?,?,R3859,?,Comp-Approve,End of Design,?,NIC1_P12V_MAM_MAM_BOM1 
268,CS00002JB13,RES CHIP 0 1/16W +-5%(0402)EF,EMPTY,1,?,?,R3860,?,Comp-Approve,End of Design,?,NIC1_P12V_MPS_MAM_BOM3 
269,CS00002JB13,RES CHIP 0 1/16W +-5%(0402)EF,EMPTY,1,?,?,R3861,?,Comp-Approve,End of Design,NIC1_P12V_MAM_TIC_BOM2 ,?
270,CS00002JB13,RES CHIP 0 1/16W +-5%(0402)EF,CHIP,1,?,?,R3862,?,Comp-Approve,End of Design,NIC1_P12V_MPS_TIC_BOM4 ,?
271,CS00002JB13,RES CHIP 0 1/16W +-5%(0402)EF,EMPTY,3,?,?,"R3863,R3867,R3869",?,Comp-Approve,End of Design,?,NIC1_P12V_MAM_MAM_BOM1
272,CS00002JB13,RES CHIP 0 1/16W +-5%(0402)EF,EMPTY,3,?,?,"R3864,R3871,R3873",?,Comp-Approve,End of Design,?,NIC1_P12V_MPS_MAM_BOM3
273,CS00002JB13,RES CHIP 0 1/16W +-5%(0402)EF,EMPTY,3,?,?,"R3865,R3868,R3870",?,Comp-Approve,End of Design,NIC1_P12V_MAM_TIC_BOM2,?
274,CS00002JB13,RES CHIP 0 1/16W +-5%(0402)EF,CHIP,3,?,?,"R3866,R3872,R3874",?,Comp-Approve,End of Design,NIC1_P12V_MPS_TIC_BOM4,?
275,CS00002JB13,RES CHIP 0 1/16W +-5%(0402)EF,EMPTY,2,?,?,"R3939,R3974",?,Comp-Approve,End of Design,?,E1S1_P12V_MAM_MAM_BOM1
276,CS00002JB13,RES CHIP 0 1/16W +-5%(0402)EF,EMPTY,2,?,?,"R3940,R3955",?,Comp-Approve,End of Design,?,E1S1_P12V_MPS_MAM_BOM3
277,CS00002JB13,RES CHIP 0 1/16W +-5%(0402)EF,EMPTY,2,?,?,"R3941,R3975",?,Comp-Approve,End of Design,E1S1_P12V_MAM_TIC_BOM2,?
278,CS00002JB13,RES CHIP 0 1/16W +-5%(0402)EF,CHIP,2,?,?,"R3942,R3956",?,Comp-Approve,End of Design,E1S1_P12V_MPS_TIC_BOM4,?
279,CS00002JB13,RES CHIP 0 1/16W +-5%(0402)EF,CHIP,1,?,?,R3943,?,Comp-Approve,End of Design,E1S1_P12V_MPS_TIC_BOM4,E1S1_P12V_MPS_MAM_BOM3
280,CS00002JB13,RES CHIP 0 1/16W +-5%(0402)EF,EMPTY,1,?,?,R3946,?,Comp-Approve,End of Design,?,E1S1_P3V3_BOM2
281,CS00002JB13,RES CHIP 0 1/16W +-5%(0402)EF,EMPTY,2,?,?,"R3958,R3972",?,Comp-Approve,End of Design,E1S1_P12V_MAM_TIC_BOM2,E1S1_P12V_MAM_MAM_BOM1
282,CS00002JB13,RES CHIP 0 1/16W +-5%(0402)EF,CHIP,3,?,?,"R3959,R3973,R4063",?,Comp-Approve,End of Design,?,E1S1_P3V3_BOM1
283,CS00002JB13,RES CHIP 0 1/16W +-5%(0402)EF,CHIP,3,?,?,"R3998,R4709,R4770",?,Comp-Approve,End of Design,?,SCM_P12V_BOM2
284,CS00002JB13,RES CHIP 0 1/16W +-5%(0402)EF,CHIP,5,?,?,"R4537,R4659,R4660,R4663,R4664",?,Comp-Approve,End of Design,?,PCIE REDRIVER1_BOM1
285,CS00002JB13,RES CHIP 0 1/16W +-5%(0402)EF,CHIP,1,?,?,R4651,?,Comp-Approve,End of Design,?,PCIE REDRIVER1_BOM2
286,CS00002JB13,RES CHIP 0 1/16W +-5%(0402)EF,EMPTY,4,?,?,"R4661,R4662,R4665,R4666",?,Comp-Approve,End of Design,?,PCIE REDRIVER1_BOM2
287,CS00002JB13,RES CHIP 0 1/16W +-5%(0402)EF,EMPTY,6,?,?,"R4684,R4691,R4693,R4894,R4895,R4896",?,Comp-Approve,End of Design,?,HSC1_BOM2
288,CS00004JA05,RES CHIP 0 1/8W +-5% (0805)EF,CHIP,1,?,?,R1747,?,Comp-Approve,End of Design,?,?
289,CS00004JA05,RES CHIP 0 1/8W +-5% (0805)EF,EMPTY,1,?,?,R1765,?,Comp-Approve,End of Design,?,?
290,CS00007T200,RES CHIP 0 1/2W (1206)EF,EMPTY,2,?,?,"R323,R329",?,Comp-Approve,End of Design,?,?
291,CS00007T200,RES CHIP 0 1/2W (1206)EF,CHIP,2,?,?,"R324,R330",?,Comp-Approve,End of Design,?,?
292,CS0000FFT04,RES CHIP 0.0003 4W +-1%(2725),EMPTY,4,RLC,LR2725-24R0003F1,"PR4,PR2532,PR2533,PR2534",?,Comp-Approve,End of Design,?,HSC1_BOM2
293,CS01002FB07,RES CHIP 10 1/16W +-1%(0402)EF,EMPTY,16,?,?,"PR2514,PR2515,PR2516,PR2517,PR2518,PR2524,PR2525,PR2526,PR2527,PR2528,PR2529,PR2530,PR2531,PR2535,PR2536,PR2538",?,Comp-Approve,End of Design,?,HSC1_BOM2
294,CS01002FB07,RES CHIP 10 1/16W +-1%(0402)EF,EMPTY,1,?,?,PR2537,?,Comp-Approve,End of Design,?,?
295,CS01002FB07,RES CHIP 10 1/16W +-1%(0402)EF,CHIP,2,?,?,"PR3782,PR3798",?,Comp-Approve,End of Design,?,NIC1_P3V3_BOM1
296,CS01002FB07,RES CHIP 10 1/16W +-1%(0402)EF,EMPTY,2,?,?,"PR3792,PR3830",?,Comp-Approve,End of Design,NIC1_P12V_MAM_TIC_BOM2,NIC1_P12V_MAM_MAM_BOM1
297,CS01002FB07,RES CHIP 10 1/16W +-1%(0402)EF,EMPTY,1,?,?,PR3966,?,Comp-Approve,End of Design,E1S1_P12V_MAM_TIC_BOM2,E1S1_P12V_MAM_MAM_BOM1
298,CS01002FB07,RES CHIP 10 1/16W +-1%(0402)EF,CHIP,1,?,?,PR3967,?,Comp-Approve,End of Design,?,E1S1_P3V3_BOM1
299,CS01002FB07,RES CHIP 10 1/16W +-1%(0402)EF,EMPTY,1,?,?,PR4003,?,Comp-Approve,End of Design,?,SCM_P12V_BOM1
300,CS01002FB07,RES CHIP 10 1/16W +-1%(0402)EF,CHIP,34,?,?,"R1,R24,R25,R53,R54,R61,R752,R753,R754,R755,R756,R763,R775,R777,R1479,R1868,R1869,R1870,R1871,R1872,R2363,R3570,R3571,R3574,R3575,R3578,R3579,R3602,R3603,R3758,R3760,R4118,R4535,R4536",?,Comp-Approve,End of Design,?,?
301,CS02202FB02,RES CHIP 22 1/16W +-1%(0402)EF,CHIP,21,?,?,"R563,R564,R565,R566,R1273,R1274,R1275,R1276,R1291,R1292,R1293,R3194,R3195,R3196,R3197,R3198,R3199,R3200,R3201,R4303,R4304",?,Comp-Approve,End of Design,?,?
302,CS02202FB02,RES CHIP 22 1/16W +-1%(0402)EF,EMPTY,5,?,?,"R1290,R3209,R3210,R3211,R3212",?,Comp-Approve,End of Design,?,?
303,CS02202FB02,RES CHIP 22 1/16W +-1%(0402)EF,CHIP,2,?,?,"R2588,R3934",?,Comp-Approve,End of Design,?,HSC1_BOM1
304,CS02202JB09,RES CHIP 22 1/16W +-5%(0402)EF,CHIP,1,?,?,R2339,?,Comp-Approve,End of Design,?,?
305,CS02742FB03,RES CHIP 27.4 1/16W +-1%(0402)EF,CHIP,4,?,?,"R1140,R1141,R2674,R3181",?,Comp-Release Qty,End of Design,?,?
306,CS03322FB03,RES CHIP 33.2 1/16W +-1%(0402)EF,CHIP,389,?,?,"R3,R7,R10,R11,R63,R67,R68,R107,R108,R109,R110,R113,R269,R315,R322,R419,R424,R425,R435,R474,R499,R501,R577,R578,R579,R580,R581,R582,R588,R589,R671,R673,R675,R677,R688,R690,R692,R694,R697,R699,R745,R803,R804,R805,R806,R880,R884,R885,R886,R889,R890,R893,R894,R895,R896,R897,R898,R899,R900,R901,R902,R903,R905,R906,R907,R908,R909,R960,R961,R962,R981,R982,R983,R984,R985,R986,R987,R988,R993,R994,R995,R996,R1100,R1130,R1131,R1205,R1206,R1207,R1263,R1268,R1300,R1306,R1307,R1309,R1310,R1313,R1395,R1423,R1442,R1443,R1444,R1446,R1447,R1448,R1469,R1470,R1472,R1504,R1505,R1514,R1520,R1526,R1594,R1595,R1600,R1606,R1656,R1657,R1661,R1662,R1693,R1719,R1736,R1751,R1752,R1753,R1754,R1755,R1756,R1757,R1758,R1811,R1812,R1827,R1843,R1844,R1919,R1921,R1932,R1933,R1934,R1935,R1995,R1996,R2113,R2362,R2371,R2372,R2410,R2411,R2417,R2418,R2419,R2420,R2421,R2422,R2423,R2424,R2425,R2449,R2450,R2453,R2454,R2455,R2456,R2477,R2478,R2479,R2480,R2489,R2498,R2499,R2500,R2501,R2502,R2503,R2504,R2505,R2661,R2662,R2663,R2664,R2671,R2672,R2675,R2726,R2727,R2728,R2729,R2730,R2731,R2732,R2733,R2734,R2735,R2736,R2738,R2796,R2811,R2812,R2844,R2845,R2846,R2847,R2897,R2898,R2939,R2944,R2990,R2991,R2995,R2996,R3036,R3043,R3050,R3052,R3053,R3054,R3056,R3057,R3058,R3059,R3060,R3061,R3063,R3065,R3112,R3113,R3114,R3156,R3157,R3158,R3185,R3186,R3187,R3188,R3189,R3191,R3193,R3203,R3228,R3229,R3230,R3231,R3234,R3238,R3239,R3301,R3324,R3340,R3341,R3397,R3476,R3477,R3478,R3479,R3480,R3481,R3482,R3483,R3484,R3485,R3486,R3496,R3497,R3505,R3533,R3534,R3553,R3554,R3568,R3569,R3572,R3573,R3576,R3577,R3586,R3587,R3588,R3589,R3590,R3591,R3592,R3593,R3594,R3595,R3600,R3601,R3711,R3712,R3754,R3756,R3858,R4021,R4022,R4023,R4042,R4043,R4044,R4045,R4046,R4047,R4048,R4049,R4050,R4051,R4052,R4057,R4087,R4089,R4143,R4144,R4145,R4146,R4147,R4148,R4149,R4150,R4151,R4152,R4157,R4170,R4171,R4172,R4174,R4175,R4178,R4179,R4180,R4181,R4182,R4183,R4259,R4266,R4267,R4392,R4393,R4394,R4399,R4400,R4407,R4408,R4413,R4414,R4477,R4478,R4479,R4480,R4481,R4495,R4496,R4497,R4502,R4505,R4506,R4507,R4508,R4509,R4510,R4512,R4530,R4540,R4541,R4556,R4557,R4558,R4563,R4608,R4609,R4610,R4611,R4612,R4614,R4616,R4617,R4618,R4621,R4677,R4714,R4715,R4723,R4746,R4747,R4751,R4754,R4755,R4760,R4765,R4771",?,Comp-Approve,End of Design,?,?
307,CS03322FB03,RES CHIP 33.2 1/16W +-1%(0402)EF,CHIP,1,?,?,R3654,?,Comp-Approve,End of Design,?,USB1_BOM1
308,CS03322FB03,RES CHIP 33.2 1/16W +-1%(0402)EF,CHIP,1,?,?,R3909,?,Comp-Approve,End of Design,?,HSC1_BOM1
309,CS03322FB03,RES CHIP 33.2 1/16W +-1%(0402)EF,EMPTY,6,?,?,"R4451,R4718,R4782,R4783,R4788,R4794",?,Comp-Approve,End of Design,?,?
310,CS03322FB03,RES CHIP 33.2 1/16W +-1%(0402)EF,EMPTY,2,?,?,"R4689,R4690",?,Comp-Approve,End of Design,?,HSC1_BOM2
311,CS04992FB07,RES CHIP 49.9 1/16W +-1%(0402)EF,CHIP,75,?,?,"PR1380,PR1390,PR1400,PR1410,R143,R195,R196,R548,R556,R558,R560,R575,R576,R698,R780,R1201,R1215,R1455,R1456,R1710,R1717,R1718,R2381,R2473,R2512,R2554,R2917,R2924,R2925,R3205,R3315,R3390,R3391,R3392,R3468,R3469,R3515,R3875,R3876,R3877,R3878,R3879,R3880,R3881,R3882,R3883,R3884,R3885,R3886,R3887,R3888,R3889,R3890,R3891,R3892,R3893,R3894,R3895,R3896,R3897,R3898,R3899,R3900,R3901,R3902,R3903,R3904,R3905,R3906,R4476,R4550,R4750,R4759,R4766,R4767",?,Comp-Approve,End of Design,?,?
312,CS04992FB07,RES CHIP 49.9 1/16W +-1%(0402)EF,EMPTY,10,?,?,"R2322,R2345,R2382,R2555,R4419,R4420,R4482,R4483,R4486,R4487",?,Comp-Approve,End of Design,?,?
313,CS04992FB07,RES CHIP 49.9 1/16W +-1%(0402)EF,EMPTY,2,?,?,"R4892,R4893",?,Comp-Approve,End of Design,?,HSC1_BOM2
314,CS04993F909,RES CHIP 49.9 1/10W +-1%(0603)EF,CHIP,2,?,?,"PR3843,PR3857",?,Comp-Approve,End of Design,NIC1_P12V_MPS_TIC_BOM4,NIC1_P12V_MPS_MAM_BOM3
315,CS04993F909,RES CHIP 49.9 1/10W +-1%(0603)EF,CHIP,1,?,?,PR3957,?,Comp-Approve,End of Design,E1S1_P12V_MPS_TIC_BOM4,E1S1_P12V_MPS_MAM_BOM3
316,CS04993F909,RES CHIP 49.9 1/10W +-1%(0603)EF,CHIP,1,?,?,PR4014,?,Comp-Approve,End of Design,?,SCM_P12V_BOM2
317,CS06042FB03,RES CHIP 60.4 1/16W +-1%(0402)EF,CHIP,1,?,?,R477,?,Comp-Approve,End of Design,?,?
318,CS07502FB04,RES CHIP 75 1/16W +-1%(0402)EF,EMPTY,1,?,?,R1025,?,Comp-Approve,End of Design,?,?
319,CS07502FB04,RES CHIP 75 1/16W +-1%(0402)EF,CHIP,6,?,?,"R742,R744,R748,R749,R774,R1266",?,Comp-Approve,End of Design,?,?
320,CS11002FB07,RES CHIP 100 1/16W +-1%(0402)EF,EMPTY,1,?,?,PR2519,?,Comp-Approve,End of Design,?,HSC1_BOM2
321,CS11002FB07,RES CHIP 100 1/16W +-1%(0402)EF,EMPTY,8,?,?,"PR3838,PR3850,PR3950,PR4006,R2354,R2386,R2426,R2656",?,Comp-Approve,End of Design,?,?
322,CS11002FB07,RES CHIP 100 1/16W +-1%(0402)EF,CHIP,93,?,?,"PR519,PR520,PR521,PR522,PR527,PR531,PR558,PR559,PR560,PR561,PR566,PR567,PR568,PR569,PR574,PR578,PR586,PR587,PR591,PR592,R2,R5,R6,R22,R23,R51,R52,R62,R65,R66,R135,R137,R151,R153,R155,R156,R157,R158,R175,R177,R179,R181,R183,R184,R185,R186,R200,R202,R219,R220,R243,R244,R328,R495,R555,R557,R559,R776,R1024,R1200,R1346,R1366,R1367,R1370,R1487,R1735,R1856,R1895,R1896,R1897,R1898,R2553,R2590,R2593,R3180,R3208,R3216,R3217,R4293,R4294,R4295,R4296,R4297,R4298,R4299,R4300,R4301,R4302,R4395,R4396,R4401,R4402,R4625",?,Comp-Approve,End of Design,?,?
323,CS11132FB02,RES CHIP 113 1/16W +-1%(0402)EF,CHIP,1,?,?,R496,?,Comp-Approve,End of Design,?,?
324,CS11202FB02,RES CHIP 120 1/16W +-1%(0402)EF,CHIP,1,?,?,R757,?,Comp-Approve,End of Design,?,?
325,CS11302FB03,RES CHIP 130 1/16W +-1%(0402)EF,CHIP,34,?,?,"R1044,R1195,R1371,R3068,R3069,R3070,R3071,R3072,R3073,R3074,R3075,R3078,R3079,R3080,R3081,R3082,R3083,R3084,R3085,R3086,R3087,R3088,R3089,R3090,R3091,R3092,R3093,R3094,R3095,R3096,R3097,R3098,R3099,R3100",?,Comp-Approve,End of Design,?,?
326,CS11502FB07,RES CHIP 150 1/16W +-1%(0402)EF,CHIP,18,?,?,"R310,R741,R743,R747,R750,R751,R758,R759,R779,R2368,R2399,R2559,R2578,R2596,R4388,R4389,R4390,R4391",?,Comp-Approve,End of Design,?,?
327,CS12002FB06,RES CHIP 200 1/16W +-1%(0402)EF,CHIP,7,?,?,"R4,R14,R17,R57,R60,R64,R497",?,Comp-Approve,End of Design,?,?
328,CS12002FB06,RES CHIP 200 1/16W +-1%(0402)EF,EMPTY,2,?,?,"R1485,R1486",?,Comp-Approve,End of Design,?,?
329,CS12402FB01,RES CHIP 240 1/16W +-1%(0402)EF,EMPTY,52,?,?,"R90,R91,R92,R93,R94,R95,R96,R97,R249,R250,R251,R255,R256,R257,R261,R262,R263,R264,R266,R267,R268,R276,R278,R279,R280,R281,R288,R289,R291,R292,R293,R294,R295,R1229,R1230,R1232,R1233,R1235,R1236,R1237,R1238,R1239,R1270,R1391,R1392,R1393,R1394,R3024,R4260,R4261,R4262,R4263",?,Comp-Approve,End of Design,?,?
330,CS12402FB01,RES CHIP 240 1/16W +-1%(0402)EF,CHIP,19,?,?,"R252,R253,R254,R258,R259,R260,R265,R275,R277,R282,R290,R910,R911,R963,R964,R969,R970,R971,R972",?,Comp-Approve,End of Design,?,?
331,CS12436F201,RES CHIP 243 1/4W +-1%(1206)EF,CHIP,4,?,?,"R4638,R4639,R4640,R4641",?,?,?,?,?
332,CS12492FB02,RES CHIP 249 1/16W +-1%(0402)EF,CHIP,4,?,?,"R366,R1241,R1243,R4711",?,Comp-Approve,End of Design,?,?
333,CS13012FB02,RES CHIP 301 1/16W +-1%(0402)EF,CHIP,8,?,?,"R197,R198,R296,R298,R301,R303,R1242,R1244",?,Comp-Approve,End of Design,?,?
334,CS14702FB04,RES CHIP 470 1/16W +-1%(0402)EF,CHIP,3,?,?,"PR1653,R3101,R3102",?,Comp-Approve,End of Design,?,?
335,CS14992FB06,RES CHIP 499 1/16W +-1%(0402)EF,CHIP,24,?,?,"PR4219,PR4226,PR4229,PR4237,PR4240,PR4241,PR4247,PR4250,PR4258,PR4265,R18,R19,R49,R50,R662,R663,R664,R669,R679,R680,R681,R686,R760,R761",?,Comp-Approve,End of Design,?,?
336,CS15602FB03,RES CHIP 560 1/16W +-1%(0402)EF,CHIP,10,?,?,"R977,R978,R979,R980,R4702,R4703,R4704,R4705,R4706,R4707",?,?,?,?,?
337,CS16802FB03,RES CHIP 680 1/16W +-1%(0402)EF,CHIP,1,?,?,R3653,?,?,?,?,USB1_BOM1
338,CS16802FB03,RES CHIP 680 1/16W +-1%(0402)EF,EMPTY,1,?,?,R4463,?,?,?,?,?
339,CS16812FB02,RES CHIP 681 1/16W +-1%(0402)EF,CHIP,1,?,?,PR106,?,Comp-Approve,End of Design,?,?
340,CS18452FB01,RES CHIP 845 1/16W +-1%(0402)EF,EMPTY,2,?,?,"PR3781,PR3823",?,Comp-Approve,End of Design,NIC1_P12V_MAM_TIC_BOM2,NIC1_P12V_MAM_MAM_BOM1
341,CS21002FB06,RES CHIP 1K 1/16W +-1%(0402)EF,EMPTY,120,?,?,"PR123,PR166,PR214,PR218,PR276,PR313,PR369,PR373,PR836,PR1850,PR3929,R87,R331,R333,R335,R367,R371,R374,R378,R380,R607,R609,R614,R617,R621,R623,R625,R627,R722,R736,R766,R920,R1008,R1009,R1123,R1127,R1132,R1197,R1220,R1298,R1390,R1475,R1477,R1484,R1494,R1498,R1676,R1764,R1810,R1814,R2398,R2509,R2511,R2514,R2573,R2693,R2695,R2973,R2978,R3025,R3037,R3149,R3151,R3153,R3160,R3269,R3270,R3271,R3272,R3275,R3276,R3277,R3280,R3281,R3283,R3286,R3287,R3289,R3290,R3381,R3667,R3669,R4184,R4186,R4188,R4190,R4192,R4194,R4196,R4198,R4200,R4202,R4204,R4206,R4273,R4274,R4275,R4279,R4280,R4281,R4284,R4285,R4287,R4288,R4588,R4596,R4634,R4642,R4643,R4644,R4645,R4646,R4648,R4649,R4650,R4655,R4657,R4658,R4804,R4805",?,Comp-Approve,End of Design,?,?
342,CS21002FB06,RES CHIP 1K 1/16W +-1%(0402)EF,CHIP,179,?,?,"PR215,PR217,PR370,PR372,R223,R307,R361,R369,R379,R420,R423,R487,R494,R537,R539,R587,R611,R615,R622,R629,R650,R661,R678,R710,R714,R718,R767,R768,R771,R772,R773,R778,R819,R820,R821,R822,R839,R840,R841,R842,R965,R966,R967,R968,R1004,R1026,R1124,R1126,R1128,R1129,R1203,R1221,R1253,R1255,R1267,R1317,R1320,R1324,R1325,R1333,R1335,R1347,R1356,R1365,R1368,R1369,R1374,R1380,R1381,R1382,R1383,R1462,R1473,R1474,R1476,R1493,R1499,R1527,R1605,R1654,R1741,R1750,R1823,R1905,R1906,R1907,R1908,R2133,R2222,R2227,R2235,R2241,R2243,R2296,R2309,R2311,R2365,R2373,R2375,R2377,R2383,R2392,R2393,R2396,R2404,R2490,R2491,R2492,R2493,R2494,R2495,R2496,R2497,R2506,R2507,R2522,R2524,R2525,R2551,R2556,R2568,R2569,R2571,R2575,R2589,R2694,R2696,R2975,R2977,R2980,R3026,R3027,R3039,R3040,R3055,R3133,R3134,R3135,R3136,R3150,R3152,R3154,R3155,R3173,R3176,R3454,R3704,R3707,R3709,R3925,R4019,R4029,R4039,R4040,R4041,R4053,R4054,R4055,R4185,R4187,R4189,R4191,R4193,R4195,R4197,R4199,R4201,R4203,R4205,R4207,R4581,R4583,R4585,R4590,R4592,R4598,R4623,R4678,R4806",?,Comp-Approve,End of Design,?,?
343,CS21002FB06,RES CHIP 1K 1/16W +-1%(0402)EF,CHIP,2,?,?,"R3278,R3284",?,Comp-Approve,End of Design,?,PCIE REDRIVER1_BOM1
344,CS21002FB06,RES CHIP 1K 1/16W +-1%(0402)EF,CHIP,7,?,?,"R3362,R3386,R4647,R4653,R4654,R4656,R4694",?,Comp-Approve,End of Design,?,PCIE REDRIVER1_BOM2
345,CS21002FB06,RES CHIP 1K 1/16W +-1%(0402)EF,CHIP,2,?,?,"R3668,R3670",?,Comp-Approve,End of Design,?,ADC1_BOM2
346,CS21212FB05,RES CHIP 1.21K 1/16W +-1%(0402)EF,CHIP,1,?,?,R1800,?,Comp-Approve,End of Design,?,?
347,CS21332FB05,RES CHIP 1.33K 1/16W +-1%(0402)EF,EMPTY,2,?,?,"PR3846,PR3856",?,?,?,?,NIC1_P3V3_BOM2
348,CS21332FB05,RES CHIP 1.33K 1/16W +-1%(0402)EF,EMPTY,1,?,?,PR4008,?,?,?,?,SCM_P12V_BOM1
349,CS21502FB07,RES CHIP 1.5K 1/16W +-1%(0402)EF,EMPTY,1,?,?,PR833,?,Comp-Approve,End of Design,?,?
350,CS21502FB07,RES CHIP 1.5K 1/16W +-1%(0402)EF,CHIP,14,?,?,"R203,R204,R205,R206,R237,R238,R1216,R1217,R4397,R4398,R4403,R4404,R4409,R4410",?,Comp-Approve,End of Design,?,?
351,CS22002BB07,RES CHIP 2K 1/16W +-0.1%(0402)EF,CHIP,10,?,?,"PR1101,PR1131,PR1133,PR3914,PR3915,PR3918,PR3986,PR3987,PR3990,PR3991",?,?,?,?,HSC1_BOM1
352,CS22002FB07,RES CHIP 2K 1/16W +-1%(0402)EF,CHIP,39,?,?,"PR1649,R106,R990,R991,R1402,R1403,R1404,R1405,R1406,R1407,R1408,R1409,R1410,R1411,R1412,R1413,R1414,R1417,R1418,R1419,R1420,R1421,R1445,R1451,R1452,R1453,R1454,R1545,R1546,R1581,R1582,R2332,R2374,R2385,R3222,R3223,R3224,R3225,R4622",?,Comp-Approve,End of Design,?,?
353,CS22002FB07,RES CHIP 2K 1/16W +-1%(0402)EF,EMPTY,19,?,?,"R992,R1302,R1319,R1326,R1327,R1328,R1329,R1330,R1384,R1385,R1386,R1387,R1388,R1398,R1415,R1416,R3062,R4533,R4791",?,Comp-Approve,End of Design,?,?
354,CS22002FB07,RES CHIP 2K 1/16W +-1%(0402)EF,EMPTY,1,?,?,R2900,?,Comp-Approve,End of Design,?,ADC1_BOM1
355,CS22202JB07,RES CHIP 2.2K 1/16W +-5%(0402)EF,CHIP,20,?,?,"R651,R652,R1089,R1090,R3395,R3396,R3535,R3536,R3582,R3583,R3723,R3724,R3725,R3726,R3727,R3728,R3729,R3730,R3731,R3732",?,Comp-Approve,End of Design,?,?
356,CS22202JB07,RES CHIP 2.2K 1/16W +-5%(0402)EF,EMPTY,18,?,?,"R592,R601,R1336,R1460,R2204,R2205,R2212,R2213,R2999,R3004,R3226,R3227,R3240,R3241,R3242,R3243,R4269,R4270",?,Comp-Approve,End of Design,?,?
357,CS22212FB06,RES CHIP 2.21K 1/16W +-1%(0402)EF,EMPTY,1,?,?,R1271,?,Comp-Approve,End of Design,?,?
358,CS22492FB05,RES CHIP 2.49K 1/16W +-1%(0402)EF,CHIP,1,?,?,PR3969,?,Comp-Approve,End of Design,?,E1S1_P3V3_BOM1
359,CS22492FB05,RES CHIP 2.49K 1/16W +-1%(0402)EF,CHIP,1,?,?,R1675,?,Comp-Approve,End of Design,?,?
360,CS22672FB03,RES CHIP 2.67K 1/16W +-1%(0402)EF,EMPTY,1,?,?,PR3970,?,Comp-Approve,End of Design,E1S1_P12V_MAM_TIC_BOM2,E1S1_P12V_MAM_MAM_BOM1
361,CS22802FB04,RES CHIP 2.8K 1/16W +-1%(0402)EF,EMPTY,1,?,?,PR3947,?,Comp-Approve,End of Design,?,E1S1_P3V3_BOM2
362,CS23572FB05,RES CHIP 3.57K 1/16W +-1%(0402)EF,CHIP,1,?,?,PR358,?,Comp-Approve,End of Design,?,?
363,CS23902JB04,RES CHIP 3.9K 1/16W +-5%(0402)EF,EMPTY,1,?,?,R4465,?,Comp-Approve,End of Design,?,?
364,CS23902JB04,RES CHIP 3.9K 1/16W +-5%(0402)EF,EMPTY,1,?,?,R5238,?,Comp-Approve,End of Design,?,USB1_BOM2
365,CS24322FB03,RES CHIP 4.32K 1/16W +-1%(0402)EF,CHIP,4,?,?,"R4016,R4036,R4037,R4038",?,Comp-Approve,End of Design,?,?
366,CS24532FB03,RES CHIP 4.53K 1/16W +-1%(0402)EF,CHIP,2,?,?,"PR3824,PR5481",?,Comp-Approve,End of Design,?,NIC1_P3V3_BOM1
367,CS24702FB06,RES CHIP 4.7K 1/16W +-1%(0402)EF,EMPTY,31,?,?,"R409,R414,R491,R567,R569,R573,R1467,R1551,R2487,R3163,R3166,R3192,R3265,R3291,R3293,R3609,R3610,R3612,R3613,R3617,R3621,R3628,R3689,R3690,R3764,R4289,R4290,R4291,R4292,R4514,R4688",?,Comp-Approve,End of Design,?,?
368,CS24702FB06,RES CHIP 4.7K 1/16W +-1%(0402)EF,CHIP,32,?,?,"R410,R415,R478,R568,R570,R574,R930,R1593,R1785,R2488,R2843,R3162,R3167,R3184,R3190,R3295,R3296,R3322,R3608,R3611,R3616,R3622,R3623,R3624,R3627,R3763,R4090,R4091,R4092,R4093,R4094,R4568",?,Comp-Approve,End of Design,?,?
369,CS24702FB06,RES CHIP 4.7K 1/16W +-1%(0402)EF,CHIP,2,?,?,"R2587,R3936",?,Comp-Approve,End of Design,?,HSC1_BOM1
370,CS24702FB06,RES CHIP 4.7K 1/16W +-1%(0402)EF,CHIP,2,?,?,"R3266,R3292",?,Comp-Approve,End of Design,?,PCIE REDRIVER1_BOM1
371,CS24702FB06,RES CHIP 4.7K 1/16W +-1%(0402)EF,EMPTY,2,?,?,"R4687,R4692",?,Comp-Approve,End of Design,?,HSC1_BOM2
372,CS24702JB10,RES CHIP 4.7K 1/16W +-5%(0402)EF,CHIP,101,?,?,"R1000,R1001,R1002,R1003,R1006,R1007,R1702,R1703,R2121,R2125,R2344,R2346,R2530,R2834,R2835,R2836,R2841,R2842,R2909,R2915,R2918,R2919,R2920,R2926,R2932,R2933,R2934,R2935,R2937,R3029,R3030,R3034,R3035,R3320,R3321,R3432,R3433,R3434,R3435,R3436,R3437,R3438,R3439,R3459,R3474,R3475,R3488,R3490,R3500,R3501,R3503,R3504,R3519,R3520,R3530,R3532,R4066,R4069,R4073,R4125,R4126,R4127,R4128,R4129,R4130,R4137,R4138,R4139,R4140,R4141,R4142,R4155,R4156,R4164,R4165,R4166,R4167,R4168,R4169,R4264,R4498,R4499,R4543,R4545,R4553,R4554,R4560,R4561,R4604,R4605,R4620,R4701,R4710,R4725,R4726,R4732,R4733,R4739,R4740,R4800,R4801",?,Comp-Approve,End of Design,?,?
373,CS24702JB10,RES CHIP 4.7K 1/16W +-5%(0402)EF,EMPTY,28,?,?,"R1331,R1332,R1712,R1713,R2355,R2668,R2670,R2805,R2807,R2820,R2911,R2912,R2914,R2916,R2923,R2940,R2946,R2948,R2950,R3317,R3448,R3451,R3506,R3773,R4265,R4546,R4549,R4555",?,Comp-Approve,End of Design,?,?
374,CS24752FB03,RES CHIP 4.75K 1/16W +-1%(0402)EF,EMPTY,7,?,?,"R145,R146,R912,R1194,R2481,R4490,R4790",?,Comp-Approve,End of Design,?,?
375,CS24752FB03,RES CHIP 4.75K 1/16W +-1%(0402)EF,CHIP,16,?,?,"R241,R242,R696,R734,R953,R1196,R1269,R1471,R1500,R1502,R2253,R4405,R4406,R4411,R4412,R4489",?,Comp-Approve,End of Design,?,?
376,CS24992BB04,RES CHIP 4.99K 1/16W +-0.1%(0402)EF,CHIP,2,?,?,"PR3927,PR3932",?,?,?,?,HSC1_BOM1
377,CS24992FB07,RES CHIP 4.99K 1/16W +-1%(0402)EF,EMPTY,1,?,?,R2238,?,Comp-Approve,End of Design,?,?
378,CS25112FB04,RES CHIP 5.11K 1/16W +-1%(0402)EF,CHIP,4,?,?,"R2907,R2908,R3038,R4567",?,Comp-Approve,End of Design,?,?
379,CS25112FB04,RES CHIP 5.11K 1/16W +-1%(0402)EF,EMPTY,2,?,?,"R4775,R4777",?,Comp-Approve,End of Design,?,?
380,CS25232FB08,RES CHIP 5.23K 1/16W +-1%(0402)EF,CHIP,1,?,?,PR318,?,?,?,?,?
381,CS25362FB02,RES CHIP 5.36K 1/16W +-1%(0402)EF,CHIP,2,?,?,"PR3780,PR3822",?,Comp-Approve,End of Design,?,NIC1_P3V3_BOM1
382,CS26192FB03,RES CHIP 6.19K 1/16W +-1%(0402)EF,CHIP,1,?,?,R1117,?,Comp-Approve,End of Design,?,HSC1_BOM1
383,CS26192FB03,RES CHIP 6.19K 1/16W +-1%(0402)EF,CHIP,1,?,?,R1689,?,Comp-Approve,End of Design,?,?
384,CS26802FB02,RES CHIP 6.8K 1/16W +-1%(0402)EF,EMPTY,2,?,?,"PR3787,PR3806",?,?,?,NIC1_P12V_MAM_TIC_BOM2,NIC1_P12V_MAM_MAM_BOM1
385,CS26802FB02,RES CHIP 6.8K 1/16W +-1%(0402)EF,EMPTY,1,?,?,PR3961,?,?,?,E1S1_P12V_MAM_TIC_BOM2,E1S1_P12V_MAM_MAM_BOM1
386,CS26802FB02,RES CHIP 6.8K 1/16W +-1%(0402)EF,EMPTY,1,?,?,PR4001,?,?,?,?,SCM_P12V_BOM1
387,CS27152FB03,RES CHIP 7.15K 1/16W +-1%(0402)EF,CHIP,2,?,?,"PR3790,PR3829",?,Comp-Approve,End of Design,?,NIC1_P3V3_BOM1
388,CS27152FB03,RES CHIP 7.15K 1/16W +-1%(0402)EF,CHIP,1,?,?,PR3964,?,Comp-Approve,End of Design,?,E1S1_P3V3_BOM1
389,CS27322BB09,RES CHIP 7.32K 1/16W +-0.1% (0402)EF,CHIP,1,?,?,PR1328,?,?,?,?,?
390,CS27872FB02,RES CHIP 7.87K 1/16W +-1%(0402)EF,CHIP,1,?,?,R1799,?,Comp-Approve,End of Design,?,?
391,CS28252BB01,RES CHIP 8.25K 1/16W +-0.1%(0402)EF,CHIP,2,?,?,"PR501,PR502",?,?,?,?,?
392,CS28452FB06,RES CHIP 8.45K 1/16W +-1%( 0402)EF,CHIP,2,?,?,"PR259,PR1327",?,?,?,?,?
393,CS28452FB06,RES CHIP 8.45K 1/16W +-1%( 0402)EF,EMPTY,1,?,?,R4716,?,?,?,?,?
394,CS28872FB01,RES CHIP 8.87K 1/16W +-1%(0402)EF,EMPTY,32,?,?,"PR132,PR133,PR138,PR139,PR144,PR145,PR150,PR151,PR224,PR225,PR285,PR286,PR291,PR292,PR297,PR298,PR325,PR326,PR353,PR354,PR1297,PR1298,PR1304,PR1305,PR1707,PR1708,PR1709,PR1726,PR1727,PR1728,PR1746,PR2718",?,Comp-Approve,End of Design,?,?
395,CS29092FB05,RES CHIP 9.09K 1/16W +-1%(0402)EF,CHIP,1,?,?,R1791,?,Comp-Approve,End of Design,?,?
396,CS29312FB02,RES CHIP 9.31K 1/16W +-1%(0402)EF,EMPTY,1,?,?,PR3968,?,Comp-Approve,End of Design,E1S1_P12V_MAM_TIC_BOM2,E1S1_P12V_MAM_MAM_BOM1
397,CS29762FB05,RES CHIP 9.76K 1/16W +-1%(0402)EF,CHIP,2,?,?,"PR1336,PR1339",?,Comp-Approve,End of Design,?,?
398,CS29762FB05,RES CHIP 9.76K 1/16W +-1%(0402)EF,CHIP,1,?,?,PR3971,?,Comp-Approve,End of Design,?,E1S1_P3V3_BOM1
399,CS31002BB06,RES CHIP 10K 1/16W +-0.1%(0402)EF,CHIP,1,?,?,PR187,?,Comp-Approve,End of Design,?,?
400,CS31002FB08,RES CHIP 10K 1/16W +-1%(0402)EF,EMPTY,105,?,?,"PR400,PR435,PR436,PR451,PR453,PR634,PR637,PR665,PR667,PR705,PR1647,R139,R148,R401,R536,R538,R540,R612,R630,R701,R702,R703,R704,R705,R706,R707,R708,R713,R717,R997,R1005,R1204,R1260,R1262,R1305,R1308,R1312,R1440,R1465,R1483,R1558,R1660,R1691,R1706,R1742,R1749,R1763,R1813,R2234,R2240,R2242,R2308,R2310,R2338,R2343,R2367,R2384,R2406,R2451,R2508,R2510,R2921,R2974,R2976,R2979,R3042,R3470,R3656,R3657,R3658,R3659,R3664,R3703,R3705,R3706,R3708,R4078,R4082,R4448,R4449,R4452,R4456,R4457,R4458,R4459,R4500,R4580,R4582,R4584,R4589,R4591,R4597,R4668,R4670,R4671,R4672,R4772,R4773,R4784,R4785,R4786,R4789,R4792,R4796,R4797",?,Comp-Approve,End of Design,?,?
401,CS31002FB08,RES CHIP 10K 1/16W +-1%(0402)EF,CHIP,2,?,?,"PR2106,PR3935",?,Comp-Approve,End of Design,?,HSC1_BOM1
402,CS31002FB08,RES CHIP 10K 1/16W +-1%(0402)EF,CHIP,6,?,?,"PR3839,PR3842,PR3851,PR3854,R3848,R4532",?,Comp-Approve,End of Design,NIC1_P12V_MPS_TIC_BOM4,NIC1_P12V_MPS_MAM_BOM3
403,CS31002FB08,RES CHIP 10K 1/16W +-1%(0402)EF,CHIP,3,?,?,"PR3951,PR3954,R3948",?,Comp-Approve,End of Design,E1S1_P12V_MPS_TIC_BOM4,E1S1_P12V_MPS_MAM_BOM3
404,CS31002FB08,RES CHIP 10K 1/16W +-1%(0402)EF,CHIP,3,?,?,"PR4007,PR4011,R3836",?,Comp-Approve,End of Design,?,SCM_P12V_BOM2
405,CS31002FB08,RES CHIP 10K 1/16W +-1%(0402)EF,CHIP,254,?,?,"PR73,R8,R26,R34,R42,R69,R70,R71,R79,R111,R147,R270,R271,R272,R273,R274,R283,R284,R285,R286,R287,R318,R319,R320,R321,R325,R326,R327,R332,R334,R372,R375,R381,R421,R422,R453,R456,R498,R515,R608,R610,R613,R618,R619,R624,R626,R628,R635,R721,R727,R735,R739,R740,R769,R770,R913,R919,R927,R928,R929,R932,R933,R934,R935,R936,R937,R938,R939,R940,R941,R942,R943,R944,R945,R946,R947,R1099,R1106,R1138,R1149,R1150,R1198,R1226,R1227,R1254,R1257,R1259,R1299,R1311,R1338,R1339,R1341,R1342,R1343,R1375,R1396,R1399,R1401,R1434,R1435,R1437,R1449,R1450,R1457,R1458,R1459,R1478,R1492,R1495,R1496,R1554,R1583,R1592,R1601,R1642,R1655,R1659,R1673,R1681,R1690,R1694,R1820,R1822,R1824,R1828,R1841,R1854,R1857,R1929,R1930,R1955,R1958,R1961,R2134,R2230,R2232,R2233,R2244,R2282,R2287,R2304,R2312,R2315,R2317,R2342,R2356,R2357,R2359,R2407,R2409,R2486,R2583,R2584,R2666,R2667,R2669,R2972,R2984,R2985,R3041,R3127,R3130,R3131,R3145,R3147,R3164,R3165,R3174,R3175,R3182,R3183,R3249,R3297,R3298,R3325,R3455,R3457,R3465,R3466,R3467,R3471,R3487,R3507,R3509,R3529,R3638,R3639,R3640,R3641,R3642,R3643,R3771,R3938,R4079,R4080,R4081,R4086,R4095,R4096,R4097,R4098,R4099,R4100,R4101,R4102,R4103,R4104,R4105,R4106,R4107,R4108,R4109,R4110,R4111,R4112,R4113,R4114,R4115,R4116,R4117,R4121,R4135,R4153,R4176,R4491,R4492,R4494,R4516,R4517,R4518,R4519,R4520,R4521,R4564,R4565,R4579,R4586,R4603,R4635,R4674,R4679,R4719,R4722,R4727,R4730,R4737,R4745,R4756,R4761,R4762,R4763,R4764,R4768,R4798",?,Comp-Approve,End of Design,?,?
406,CS31002FB08,RES CHIP 10K 1/16W +-1%(0402)EF,CHIP,2,?,?,"R3660,R3663",?,Comp-Approve,End of Design,?,USB1_BOM1
407,CS31002FB08,RES CHIP 10K 1/16W +-1%(0402)EF,EMPTY,2,?,?,"R4065,R4068",?,Comp-Approve,End of Design,NIC1_P12V_MAM_TIC_BOM2,NIC1_P12V_MAM_MAM_BOM1
408,CS31002FB08,RES CHIP 10K 1/16W +-1%(0402)EF,CHIP,2,?,?,"R4067,R4070",?,Comp-Approve,End of Design,?,NIC1_P3V3_BOM1
409,CS31002FB08,RES CHIP 10K 1/16W +-1%(0402)EF,EMPTY,1,?,?,R4071,?,Comp-Approve,End of Design,?,SCM_P12V_BOM1
410,CS31002FB08,RES CHIP 10K 1/16W +-1%(0402)EF,CHIP,1,?,?,R4072,?,Comp-Approve,End of Design,?,E1S1_P3V3_BOM1
411,CS31002FB08,RES CHIP 10K 1/16W +-1%(0402)EF,EMPTY,1,?,?,R4074,?,Comp-Approve,End of Design,E1S1_P12V_MAM_TIC_BOM2,E1S1_P12V_MAM_MAM_BOM1
412,CS31052FB03,RES CHIP 10.5K 1/16W +-1%(0402)EF,EMPTY,2,?,?,"R4685,R4686",?,?,?,?,HSC1_BOM2
413,CS31132BB02,RES CHIP 11.3K 1/16W +-0.1%(0402)EF,CHIP,2,?,?,"PR1310,PR1314",?,?,?,?,?
414,CS31182BB06,RES CHIP 11.8K 1/16W +-0.1%(0402)EF,CHIP,1,?,?,PR91,?,?,?,?,?
415,CS31202FB04,RES CHIP 12K 1/16W +-1%(0402)EF,EMPTY,1,?,?,R1497,?,Comp-Approve,End of Design,?,?
416,CS31242BB10,RES CHIP 12.4K 1/16W +-0.1%( 0402)EF,CHIP,2,?,?,"PR50,PR51",?,?,?,?,?
417,CS31432FB02,RES CHIP 14.3K 1/16W +-1%(0402)EF,CHIP,2,?,?,"PR3835,PR3847",?,Comp-Approve,End of Design,NIC1_P12V_MPS_TIC_BOM4,NIC1_P12V_MPS_MAM_BOM3
418,CS31502BB03,RES CHIP 15K  1/16W +-0.1%(0402)EF,CHIP,1,?,?,PR830,?,Comp-Approve,End of Design,?,?
419,CS31502FB05,RES CHIP 15K 1/16W +-1%(0402)EF,EMPTY,2,?,?,"PR3788,PR3828",?,Comp-Approve,End of Design,NIC1_P12V_MAM_TIC_BOM2,NIC1_P12V_MAM_MAM_BOM1
420,CS31502FB05,RES CHIP 15K 1/16W +-1%(0402)EF,CHIP,2,?,?,"PR3791,PR3812",?,Comp-Approve,End of Design,?,NIC1_P3V3_BOM1
421,CS31502FB05,RES CHIP 15K 1/16W +-1%(0402)EF,EMPTY,1,?,?,PR3962,?,Comp-Approve,End of Design,E1S1_P12V_MAM_TIC_BOM2,E1S1_P12V_MAM_MAM_BOM1
422,CS31502FB05,RES CHIP 15K 1/16W +-1%(0402)EF,CHIP,1,?,?,PR3965,?,Comp-Approve,End of Design,?,E1S1_P3V3_BOM1
423,CS31502FB05,RES CHIP 15K 1/16W +-1%(0402)EF,EMPTY,1,?,?,PR4002,?,Comp-Approve,End of Design,?,SCM_P12V_BOM1
424,CS31542FB02,RES CHIP 15.4K 1/16W +-1%(0402)EF,CHIP,4,?,?,"R27,R35,R43,R78",?,?,?,?,?
425,CS31692FB03,RES CHIP 16.9K 1/16W +-1%(0402)EF,CHIP,1,?,?,PR89,?,Comp-Approve,End of Design,?,?
426,CS31692FB03,RES CHIP 16.9K 1/16W +-1%(0402)EF,CHIP,1,?,?,R3933,?,Comp-Approve,End of Design,?,HSC1_BOM1
427,CS31742FB04,RES CHIP 17.4K 1/16W +-1%(0402)EF,CHIP,2,?,?,"PR3837,PR3849",?,Comp-Approve,End of Design,NIC1_P12V_MPS_TIC_BOM4,NIC1_P12V_MPS_MAM_BOM3
428,CS31782FB04,RES CHIP 17.8K 1/16W +- 1% (0402)EF,EMPTY,1,?,?,PR4004,?,Comp-Approve,End of Design,?,SCM_P12V_BOM1
429,CS31782FB04,RES CHIP 17.8K 1/16W +- 1% (0402)EF,EMPTY,2,?,?,"R4774,R4776",?,Comp-Approve,End of Design,?,?
430,CS31802FB04,RES CHIP 18K 1/16W +-1%(0402)EF,CHIP,1,?,?,R3005,?,?,?,?,?
431,CS32002FB06,RES CHIP 20K 1/16W +-1%(0402)EF,CHIP,1,?,?,PR4540,?,Comp-Approve,End of Design,?,SCM_P12V_BOM2
432,CS32002FB06,RES CHIP 20K 1/16W +-1%(0402)EF,CHIP,1,?,?,PR4541,?,Comp-Approve,End of Design,E1S1_P12V_MPS_TIC_BOM4,E1S1_P12V_MPS_MAM_BOM3
433,CS32002FB06,RES CHIP 20K 1/16W +-1%(0402)EF,CHIP,4,?,?,"R502,R1202,R1340,R1809",?,Comp-Approve,End of Design,?,?
434,CS32002FB06,RES CHIP 20K 1/16W +-1%(0402)EF,EMPTY,1,?,?,R1962,?,Comp-Approve,End of Design,?,?
435,CS32152FB04,RES CHIP 21.5K 1/16W +-1%(0402)EF,CHIP,1,?,?,PR834,?,?,?,?,?
436,CS32262FB02,RES CHIP 22.6K 1/16W +-1%(0402)EF,CHIP,1,?,?,PR1303,?,Comp-Approve,End of Design,?,?
437,CS32322FB03,RES CHIP 23.2K 1/16W +-1%(0402)EF,CHIP,4,?,?,"R28,R36,R44,R77",?,Comp-Approve,End of Design,?,?
438,CS32432FB03,RES CHIP 24.3K 1/16W +-1%(0402)EF,CHIP,1,?,?,PR203,?,?,?,?,?
439,CS32432FB03,RES CHIP 24.3K 1/16W +-1%(0402)EF,CHIP,1,?,?,PR3999,?,?,?,?,SCM_P12V_BOM2
440,CS32552FB06,RES CHIP 25.5K 1/16W +-1%(0402)EF,CHIP,2,?,?,"PR3789,PR3795",?,Comp-Approve,End of Design,?,NIC1_P3V3_BOM1
441,CS32552FB06,RES CHIP 25.5K 1/16W +-1%(0402)EF,CHIP,1,?,?,PR3963,?,Comp-Approve,End of Design,?,E1S1_P3V3_BOM1
442,CS32612BB02,RES CHIP 26.1K 1/16W +-0.1%(0402)EF,EMPTY,2,?,?,"PR2336,PR2381",?,?,?,?,?
443,CS32672FB03,RES CHIP 26.7K 1/16W +-1%(0402)EF,CHIP,2,?,?,"R2219,R2221",?,Comp-Approve,End of Design,?,?
444,CS32802FB05,RES CHIP 28K 1/16W +-1%(0402)EF,EMPTY,6,?,?,"PR105,PR159,PR202,PR258,PR306,PR357",?,Comp-Approve,End of Design,?,?
445,CS33012FB03,RES CHIP 30.1K 1/16W +-1%(0402)EF,CHIP,2,?,?,"PR3335,PR3336",?,Comp-Approve,End of Design,?,?
446,CS33012FB03,RES CHIP 30.1K 1/16W +-1%(0402)EF,EMPTY,2,?,?,"PR3821,PR5484",?,Comp-Approve,End of Design,NIC1_P12V_MAM_TIC_BOM2,NIC1_P12V_MAM_MAM_BOM1
447,CS33012FB03,RES CHIP 30.1K 1/16W +-1%(0402)EF,CHIP,1,?,?,PR4005,?,Comp-Approve,End of Design,?,SCM_P12V_BOM2
448,CS33162FB02,RES CHIP 31.6K 1/16W +-1%(0402)EF,CHIP,1,?,?,R2585,?,Comp-Approve,End of Design,?,?
449,CS33302FB00,RES CHIP 33K 1/16W +-1%(0402)EF,CHIP,1,?,?,R3907,?,?,?,?,?
450,CS33482FB04,RES CHIP 34.8K 1/16W +-1%(0402)EF,CHIP,1,?,?,PR2222,?,?,?,?,?
451,CS33572FB01,RES CHIP 35.7K 1/16W +-1%(0402) EF,CHIP,4,?,?,"R29,R37,R45,R76",?,Comp-Approve,End of Design,?,?
452,CS33832BB06,RES CHIP 38.3K 1/16W +-0.1%(0402)EF,CHIP,2,?,?,"PR1337,PR1340",?,?,?,?,?
453,CS34642FB02,RES CHIP 46.4K 1/16W +-1%(0402)EF,CHIP,1,?,?,PR3944,?,?,?,E1S1_P12V_MPS_TIC_BOM4,E1S1_P12V_MPS_MAM_BOM3
454,CS34702BB05,RES CHIP 47K 1/16W +-0.1%(0402)EF,CHIP,1,?,?,PR831,?,?,?,?,?
455,CS34702BB05,RES CHIP 47K 1/16W +-0.1%(0402)EF,EMPTY,2,?,?,"R3661,R4453",?,?,?,?,?
456,CS35492FB03,RES CHIP 54.9K 1/16W  +-1%(0402)EF,CHIP,20,?,?,"R30,R38,R46,R75,R3461,R3463,R3464,R3492,R3494,R3498,R3508,R3510,R3511,R3513,R3514,R3521,R3522,R3523,R3524,R3525",?,Comp-Approve,End of Design,?,?
457,CS35492FB03,RES CHIP 54.9K 1/16W  +-1%(0402)EF,EMPTY,8,?,?,"R4119,R4123,R4131,R4133,R4158,R4160,R4162,R4551",?,Comp-Approve,End of Design,?,?
458,CS35602FB00,RES CHIP 56K 1/16W +-1%(0402)EF,CHIP,1,?,?,PR3949,?,?,?,E1S1_P12V_MPS_TIC_BOM4,E1S1_P12V_MPS_MAM_BOM3
459,CS36042FB04,RES CHIP 60.4K 1/16W +-1%(0402)EF,CHIP,2,?,?,"PR1301,PR2220",?,Comp-Approve,End of Design,?,?
460,CS36342FB04,RES CHIP 63.4K 1/16W +-1%(0402)EF,CHIP,1,?,?,R3923,?,Comp-Approve,End of Design,?,?
461,CS36802FB04,RES CHIP 68K 1/16W +-1%(0402)EF,EMPTY,8,?,?,"R3267,R3268,R3273,R3274,R3279,R3282,R3285,R3288",?,Comp-Approve,End of Design,?,?
462,CS36802FB04,RES CHIP 68K 1/16W +-1%(0402)EF,CHIP,2,?,?,"R4276,R4282",?,Comp-Approve,End of Design,?,?
463,CS37152FB05,RES CHIP 71.5K 1/16W +-1%(0402)EF,EMPTY,4,?,?,"PR3840,PR3852,PR3952,PR4009",?,?,?,?,?
464,CS37152FB05,RES CHIP 71.5K 1/16W +-1%(0402)EF,EMPTY,2,?,?,"PR3844,PR3855",?,?,?,?,NIC1_P3V3_BOM2
465,CS37152FB05,RES CHIP 71.5K 1/16W +-1%(0402)EF,EMPTY,1,?,?,PR3945,?,?,?,?,E1S1_P3V3_BOM2
466,CS37502BB01,RES CHIP 75K 1/16W +-0.1%(0402)EF,CHIP,2,?,?,"PR3926,PR3931",?,?,?,?,HSC1_BOM1
467,CS38202FB01,RES CHIP 82K  1/16W +-1% (0402)EF,CHIP,1,?,?,R4901,?,Comp-Approve,End of Design,?,?
468,CS38452FB05,RES CHIP 84.5K 1/16W +-1%(0402)EF,CHIP,4,?,?,"R31,R39,R47,R74",?,Comp-Approve,End of Design,?,?
469,CS38662FB05,RES CHIP 86.6K 1/16W +-1%(0402)EF,CHIP,1,?,?,PR92,?,Comp-Approve,End of Design,?,?
470,CS38662FB05,RES CHIP 86.6K 1/16W +-1%(0402)EF,EMPTY,1,?,?,R3118,?,Comp-Approve,End of Design,?,?
471,CS41002FB09,RES CHIP 100K 1/16W +-1%(0402)EF,CHIP,38,?,?,"R413,R1289,R1350,R1351,R1352,R1353,R1354,R1355,R1541,R1571,R1641,R1643,R1688,R1692,R2457,R2528,R2828,R2830,R2832,R2838,R2927,R2941,R3132,R3207,R3232,R3235,R3449,R3452,R4515,R4548,R4552,R4559,R4680,R4681,R4682,R4712,R4713,R4769",?,Comp-Approve,End of Design,?,?
472,CS41002FB09,RES CHIP 100K 1/16W +-1%(0402)EF,EMPTY,47,?,?,"R2236,R2252,R2815,R2829,R2831,R2833,R2837,R2910,R2936,R3028,R3032,R3318,R3428,R3429,R3430,R3431,R3453,R3456,R3460,R3462,R3473,R3489,R3491,R3493,R3495,R3502,R3512,R4120,R4122,R4124,R4132,R4134,R4136,R4154,R4159,R4161,R4163,R4173,R4464,R4544,R4547,R4562,R4724,R4731,R4738,R4799,R4808",?,Comp-Approve,End of Design,?,?
473,CS41002FB09,RES CHIP 100K 1/16W +-1%(0402)EF,CHIP,1,?,?,R3665,?,Comp-Approve,End of Design,?,USB1_BOM1
474,CS41002FB09,RES CHIP 100K 1/16W +-1%(0402)EF,CHIP,4,?,?,"R3783,R3796,R3826,R3833",?,Comp-Approve,End of Design,?,NIC1_P3V3_BOM1
475,CS41002FB09,RES CHIP 100K 1/16W +-1%(0402)EF,EMPTY,4,?,?,"R3797,R3799,R3816,R3825",?,Comp-Approve,End of Design,NIC1_P12V_MAM_TIC_BOM2,NIC1_P12V_MAM_MAM_BOM1
476,CS41002FB09,RES CHIP 100K 1/16W +-1%(0402)EF,EMPTY,2,?,?,"R3976,R3978",?,Comp-Approve,End of Design,E1S1_P12V_MAM_TIC_BOM2,E1S1_P12V_MAM_MAM_BOM1
477,CS41002FB09,RES CHIP 100K 1/16W +-1%(0402)EF,CHIP,2,?,?,"R3977,R3979",?,Comp-Approve,End of Design,?,E1S1_P3V3_BOM1
478,CS41002FB09,RES CHIP 100K 1/16W +-1%(0402)EF,EMPTY,2,?,?,"R4013,R4015",?,Comp-Approve,End of Design,?,SCM_P12V_BOM1
479,CS41202FB05,RES CHIP 120K 1/16W +-1%(0402)EF,CHIP,5,?,?,"PR1134,PR3912,PR3937,PR3982,PR3984",?,?,?,?,HSC1_BOM1
480,CS41202FB05,RES CHIP 120K 1/16W +-1%(0402)EF,CHIP,2,?,?,"PR3841,PR3853",?,?,?,NIC1_P12V_MPS_TIC_BOM4,NIC1_P12V_MPS_MAM_BOM3
481,CS41202FB05,RES CHIP 120K 1/16W +-1%(0402)EF,CHIP,1,?,?,PR3953,?,?,?,E1S1_P12V_MPS_TIC_BOM4,E1S1_P12V_MPS_MAM_BOM3
482,CS41202FB05,RES CHIP 120K 1/16W +-1%(0402)EF,CHIP,1,?,?,PR4010,?,?,?,?,SCM_P12V_BOM2
483,CS41272FB07,RES CHIP 127K 1/16W +-1%(0402)EF,CHIP,4,?,?,"R32,R40,R48,R73",?,?,?,?,?
484,CS41502FB04,RES CHIP 150K 1/16W +-1%(0402)EF,CHIP,1,?,?,PR1330,?,Comp-Approve,End of Design,?,?
485,CS41602FB05,RES CHIP 160K 1/16W+-1%(0402)EF,EMPTY,2,?,?,"PR3786,PR3805",?,?,?,NIC1_P12V_MAM_TIC_BOM2,NIC1_P12V_MAM_MAM_BOM1
486,CS41602FB05,RES CHIP 160K 1/16W+-1%(0402)EF,EMPTY,1,?,?,PR3960,?,?,?,E1S1_P12V_MAM_TIC_BOM2,E1S1_P12V_MAM_MAM_BOM1
487,CS41602FB05,RES CHIP 160K 1/16W+-1%(0402)EF,EMPTY,1,?,?,PR4000,?,?,?,?,SCM_P12V_BOM1
488,CS41602FB05,RES CHIP 160K 1/16W+-1%(0402)EF,EMPTY,3,?,?,"R4667,R4669,R4795",?,?,?,?,?
489,CS41962FB03,RES CHIP 196K 1/16W +-1%(0402)EF,CHIP,4,?,?,"R33,R41,R72,R80",?,Comp-Approve,End of Design,?,?
490,CS42002FB05,RES CHIP 200K 1/16W +-1%(0402)EF,CHIP,4,?,?,"R1700,R4211,R4636,R4637",?,Comp-Approve,End of Design,?,?
491,CS42002FB05,RES CHIP 200K 1/16W +-1%(0402)EF,EMPTY,5,?,?,"R2476,R3531,R4208,R4209,R4210",?,Comp-Approve,End of Design,?,?
492,CS42003B902,RES CHIP 200K 1/10W +-0.1%(0603)EF,EMPTY,1,?,?,R1316,?,Comp-Approve,End of Design,?,?
493,CS45102JB03,RES CHIP 510K 1/16W +-5%(0402)EF,EMPTY,1,?,?,R3117,?,Comp-Approve,End of Design,?,?
494,CS51002FB05,RES CHIP 1M 1/16W +-1%(0402)EF,CHIP,3,?,?,"R2966,R4778,R4779",?,Comp-Approve,End of Design,?,?
495,CS51002FB05,RES CHIP 1M 1/16W +-1%(0402)EF,EMPTY,2,?,?,"R4787,R4793",?,Comp-Approve,End of Design,?,?
496,CS61002FB02,RES CHIP 10M 1/16W +-1%(0402)EF,EMPTY,2,?,?,"PR4522,PR4524",?,?,?,NIC1_P12V_MAM_TIC_BOM2,NIC1_P12V_MAM_MAM_BOM1
497,CS61002FB02,RES CHIP 10M 1/16W +-1%(0402)EF,CHIP,2,?,?,"PR4523,PR4525",?,?,?,?,NIC1_P3V3_BOM1
498,CS61002FB02,RES CHIP 10M 1/16W +-1%(0402)EF,EMPTY,1,?,?,PR4526,?,?,?,?,SCM_P12V_BOM1
499,CS61002FB02,RES CHIP 10M 1/16W +-1%(0402)EF,CHIP,1,?,?,PR4527,?,?,?,?,E1S1_P3V3_BOM1
500,CS61002FB02,RES CHIP 10M 1/16W +-1%(0402)EF,EMPTY,1,?,?,PR4528,?,?,?,E1S1_P12V_MAM_TIC_BOM2,E1S1_P12V_MAM_MAM_BOM1
501,CS61003F901,RES CHIP 10M 1/10W +-1%(0603)EF,CHIP,1,?,?,R120,?,Comp-Approve,End of Design,?,?
502,CV+10G0MZ04,IND SMD 100NH 20% 16A(HCBS4545-101),IND,8,?,?,"PL6,PL14,PL23,PL43,PL44,PL45,PL101,PL110",?,?,?,?,?
503,CV+12^0EZ03,IND SMD 120NH 15% 69A(PGL6312.121AHLT),IND,8,?,?,"PL4,PL5,PL17,PL21,PL22,PL35,PL105,PL106",?,?,?,?,?
504,CV+13^0KZ11,IND SMD 130NH 10% 106A(PG2323.131HLT),IND,8,?,?,"PL2,PL12,PL18,PL19,PL33,PL34,PL113,PL210",?,Comp-Approve,End of Design,?,?
505,CV+15^0TZ04,IND SMD 150NH 15% 82A(PGL6303.151HLT),IND,16,PLE,PGL6303.151HLT,"PL7,PL8,PL9,PL10,PL11,PL13,PL24,PL25,PL26,PL27,PL28,PL29,PL30,PL31,PL112,PL114",?,Comp-Approve,End of Design,?,?
506,CV+30Y0KZ05,IND SMD 300NH 10% 33A(PG1712.301AHLT),IND,3,?,?,"PL3,PL20,PL150",?,?,?,?,?
507,CV+68F5MZ05,"IND SMD 0.68U +-20%,15.5A PCMC063T-R68MN",IND,2,?,?,"PL118,PL119",?,?,?,?,?
508,CV-15^0MZ02,IND SMD 1.5UH 20% 53A(EM-15AM17VG1-QS),IND,1,?,?,PL66,?,?,?,?,?
509,CV-2280MZ15,IND SMD 2.2UH +-20% 8A(PCMC063T-2R2MN),IND,1,?,?,PL170,?,?,?,?,?
510,CV-4755MZ12,IND SMD 4.7U20%5.5A(PCMC063T-4R7MN),IND,2,?,?,"PL120,PL121",?,?,?,?,?
511,CV-47A0MZ10,IND SMD 4.7UH +-20% 10A(PCMB104E-4R7MS),IND,1,?,?,PL65,?,?,?,?,?
512,CVA50^0EZ01,IND SMD 50NH 15% 148A(PGL6189.500HLT),IND,2,?,?,"PL15,PL32",?,Comp-Approve,End of Design,?,?
513,CX220TN1001,"EMI FILTER BLM18SN220TN1D(22,8000MA)",IND,2,?,?,"PL16,PL64",?,Comp-Approve,End of Design,?,?
514,CX5PX121001,"EMI FILTER BLM15PX121SN1D(120,2A)",IND,1,?,?,L18,?,?,?,?,?
515,CX5PX121001,"EMI FILTER BLM15PX121SN1D(120,2A)",EMPTY,1,?,?,L2,?,?,?,?,?
516,CX601T05003,"EMI FILTER FCM2012KF-601T05(600,0.5A)",IND,6,?,?,"L1,L13,L14,L17,L19,L20",?,?,?,?,?
517,CX8PG121009,"EMI FILTER BLM18PG121SN(120,2000MA)",EMPTY,1,?,?,L10,?,?,?,?,?
518,CX8PG300001,"EMI FILTER SBK160808T-100Y-N(10,500MA)",EMPTY,1,?,?,L15,?,?,?,?,ADC1_BOM1
519,CX8PG300001,"EMI FILTER SBK160808T-100Y-N(10,500MA)",IND,1,?,?,L16,?,?,?,?,ADC1_BOM2
520,CX8SG331000,"EMI FILTER BLM18SG331TN1D(330,1.5A)",IND,2,?,?,"L3,L4",?,Comp-Approve,End of Design,?,?
521,DFHD03MS213,"CONN DIP HEADER 3P 1R MS(P2.54,H8.6)",IO,6,PRX,210-HP1-030BR1,"JP7,JP10,JP15,JP16,JP4003,PJP1",?,?,?,?,?
522,DFHD03MS213,"CONN DIP HEADER 3P 1R MS(P2.54,H8.6)",EMPTY,2,PRX,210-HP1-030BR1,"JP4,JP9",?,?,?,?,?
523,DFHD08MS392,"CONN DIP HEADER 8P 1R MS(P2.54,H8.6)",IO,1,PRX,210-HP1-080BR1,J43,?,?,?,?,?
524,DFHD14MS170,"CONN DIP HEADER 14P 2R MS(P2.54,H8.6)",IO,1,PRX,210-HP2-07GBR1,J104,?,?,?,?,?
525,DFHD20MS193,"CONN SMD HEADER 20P 2R MS(P2,H6.4)",IO,1,ACS,51386-0200C-V01,J100,?,?,?,?,?
526,DFHD60MR024,"CONN DIP HEADER 60P 4R MR(P2.54,H12.57)",IO,1,APL,10106263-6003K02LF,J45,?,?,?,?,?
527,DFHS02FR062,"CONN DIP HOUSING 2P 1R FR(P20,H8.80)",IO,1,LTS,AAA-BAT-029-Y19,BT1,?,?,?,?,?
528,DFHS03FR030,CONN DIP HOUSING 3P 1R FR(H14.7),IO,2,APL,10165288-101LF,"J122,J123",?,?,?,?,?
529,DFHS21FS003,"CONN SMD HOUSING 21P 2R FS(P1,H3.28)",EMPTY,1,APL,91930-31121LF,PJ42,?,?,?,?,HSC1_BOM2
530,DFHS56FS022,"CONN SMD HOUSING 56P 2R FS(P0.6, H9.25)",IO,1,TYC,1-2327679-3,J90,?,?,?,?,?
531,DFHS60FS108,"CONN SMD HOUSING 60P 2R FS(P0.5,H3.05)",IO,1,STC,ASP-214108-01,J42,?,?,?,?,?
532,DFHS75FR313,"CONN SMD HOUSING 75P 2R FR(P0.5,H6.7)",IO,1,LTS,APCI0155-P004A,J59,?,?,?,?,?
533,DFHSB2FR012,"CONN DIP HOUSING 112P 8R FR(P1.2,H17.9)",IO,7,BER,10137002-101LF,"J105,J106,J107,J108,J109,J110,J111",?,?,?,?,?
534,DFHSG0FR007,"CONN DIP HOUSING 160P 8R FR(P1.2,H25.1)",IO,1,BER,10131762-101LF,J112,?,?,?,?,?
535,DFHSG8FR011,"CONN SMD HOUSING 168P 2R FR(P0.6,H5.35)",IO,3,APL,ME1016810202011,"J35,J37,J41",?,?,?,?,?
536,DFHST8FS460,"CONN SMD HS DDR5 288P 2R FS(P0.85,H21.3)",IO,16,LTS,ADR50017-P087CC,"J2,J4,J6,J8,J10,J12,J14,J16,J18,J20,J22,J24,J26,J28,J30,J32",?,?,?,?,?
537,DFHST8FS461,"CONN SMD HS DDR5 288P 2R FS(P0.85,H21.3)",IO,16,LTS,ADR50017-P130CC,"J1,J3,J5,J7,J9,J11,J13,J15,J17,J19,J21,J23,J25,J27,J29,J31",?,?,?,?,?
538,DGA^7000023,"SOCKET 4677P E LGA(P0.9398,H8.64)",IO,2,LTS,AZIF0045-P001C01CS,"U1,U2",?,?,?,?,?
539,DHP00061N15,SWITCH TACT SMD DTSM-61N-S-Q-T/R,MECH,1,DIP,DTSM-61N-S-Q-T/R,SW5,?,?,?,?,?
540,DKK00XFU000,"FUSE SMD 20A/125V(FAST,UL/CSA)",IC,1,?,?,FS1,?,?,?,?,?
541,DUMMY1,QUANTA_LOGO_7X26,EMPTY,1,?,?,ME17,?,?,?,?,?
542,DUMMY10,MECHANIC_SYMBOL,MECH,1,?,?,DM9,?,?,?,?,?
543,DUMMY12,BATTERY_SYMBOL,MECH,1,?,?,DM13,?,?,?,?,?
544,DUMMY2,WEEE,EMPTY,1,?,?,ME18,?,?,?,?,?
545,DUMMY28_HCLU2002010,"EFI BIOS LABEL LU2(HCLU2002,REV3A)",EMPTY,1,?,?,ME28,?,?,?,?,?
546,DUMMY3,PB-E1_SMALL,EMPTY,1,?,?,ME20,?,?,?,?,?
547,DUMMY36,SNLABEL_15X5,EMPTY,1,?,?,ME29,?,?,?,?,?
548,DUMMY46,SNLABEL_27X6,EMPTY,1,?,?,ME22,?,?,?,?,?
549,DUMMY47,CBS_3MMX558-8MM,EMPTY,1,?,?,ME27,?,?,?,?,?
550,DUMMY48,PICKUP_SMDC20,EMPTY,10,?,?,"ME2,ME3,ME4,ME9,ME10,ME11,ME12,ME13,ME14,ME15",?,?,?,?,?
551,DUMMY50,HOLE_TOOLINGD125N_T2-0,EMPTY,4,?,?,"H27,H28,H29,H30",?,?,?,?,?
552,DUMMY7,PCB_VENDOR_LOGO_15X8,EMPTY,1,?,?,ME21,?,?,?,?,?
553,GND_HOLE140,GNDHOLE_8PIN_C10D5-5B10,EMPTY,2,?,?,"H111,H112",?,?,?,?,?
554,GND_HOLE514,GND_C10D6-5B10_NPM_RB_NSP,EMPTY,1,?,?,H115,?,?,?,?,?
555,HOLE1079,HOLE_D3-429N,EMPTY,12,?,?,"H15,H16,H17,H18,H19,H20,H21,H22,H23,H24,H25,H26",?,?,?,?,?
556,HOLE1187,HOLE_R4-2X5D2B4_IX0-1T_NPM_RB,EMPTY,2,?,?,"H76,H77",?,?,?,?,?
557,HOLE1195,HOLE_C8D4-2B8_NPB,EMPTY,1,?,?,H129,?,?,?,?,?
558,HOLE1199,G_HOLE_C8D3-2B8I5_RO6_NPB (FOR SEL),EMPTY,4,?,?,"H44,H45,H47,H49",?,?,?,?,?
559,HOLE1247,HOLE_OB6-4X8OBD3-2X4-8B6-4X8N_RO6X7-6_NPM,EMPTY,2,?,?,"H74,H75",?,?,?,?,?
560,HOLE1248,HOLE_C4-5D3-8B8I5-6_RO6-6_NPT_RB,EMPTY,2,?,?,"H31,H32",?,?,?,?,?
561,HOLE372,HOLE_C5D3-1N,EMPTY,1,?,?,H90,?,?,?,?,?
562,HOLE596,HOLE_C10D5-6B10_NPB,EMPTY,21,?,?,"H86,H87,H88,H89,H91,H92,H93,H94,H95,H96,H97,H98,H99,H100,H101,H102,H103,H104,H105,H106,H128",?,?,?,?,?
563,N_A,"(USE SYM_2)TDR 3PIN,2X141MIL 1X100MIL P2P",EMPTY,16,?,?,"DB1,DB2,DB3,DB4,DB5,DB6,DB7,DB8,DB9,DB10,DB11,DB12,DB13,DB14,DB15,DB16",?,?,?,?,?
564,N_A,DIFF_TEST_PAD DIP FOR FTS ONLY,EMPTY,32,?,?,"X1,X2,X3,X4,X5,X6,X7,X8,X9,X10,X11,X12,X13,X14,X15,X16,X17,X18,X19,X20,X21,X22,X23,X24,X25,X26,X27,X28,X29,X30,X31,X32",?,?,?,?,?
565,SHORT6,"JUMP,SHORT_R0603",EMPTY,16,?,?,"PJ45,PJ46,PJ47,PJ48,PJ49,PJ50,PJ51,PJ52,PJ53,PJ54,PJ62,PJ63,PJ64,PJ65,PJ66,PJ67",?,?,?,?,?
566,TMP-C_T2I_ALEX_1121_1,HOLE_D10N,EMPTY,6,?,?,"H120,H122,H124,H125,H126,H127",?,?,?,?,?
567,TMP-QGND_HOLE12,GND_C8D4B8,EMPTY,2,?,?,"H113,H114",?,?,?,?,?
568,TMP-Q_HOLE78,HOLE_D3-1N,EMPTY,2,?,?,"H36,H38",?,?,?,?,?
569,TP12_BOM,?,NA,1,?,?,J90_CON,DFHS56FR016,?,?,?,?
570,TP12_BOM,?,NA,3,?,?,"JP15_23,JP16_23,JP4003_12",DEJP0020021,?,?,?,?
571,TP12_BOM,?,NA,2,?,?,"U1_BL,U2_BL",DGRA^000178,?,?,?,?
572,TP12_BOM,?,NA,2,?,?,"U1_BP,U2_BP",DGRA^000128,?,?,?,?
573,TP12_BOM,?,NA,2,?,?,"U1_DC,U2_DC",DGRA^000180,?,?,?,?
574,TP33,Probe for DELTA-L 4.0 measurement,EMPTY,32,?,?,"J63,J64,J65,J66,J67,J68,J69,J70,J71,J72,J73,J74,J75,J76,J77,J78,J79,J80,J81,J82,J83,J84,J85,J86,J114,J115,J116,J117,J118,J119,J120,J121",?,?,?,?,?
TOTAL, , , ,6080, , , , , , , , 
